FILE_TYPE = MACRO_DRAWING;
SET COLOR_WIRE YELLOW;
SET COLOR_PROP ORANGE;
SET COLOR_DOT WHITE;
SET COLOR_ARC YELLOW;
SET COLOR_BODY GREEN;
SET COLOR_NOTE PURPLE;
SET PROP_DISPLAY VALUE;
SET PAGE_NUMBER P82;
FORCEADD VCC_CORE..1
(-1550 2125);
FORCEPROP 3 LASTPIN (-1550 2075) SIG_NAME P3V3_STBY\g
J 0
(-1540 2085);
DISPLAY 0.659574 (-1540 2085);
PAINT MONO (-1540 2085);
DISPLAY INVISIBLE (-1540 2085);
FORCEPROP 1 LAST HDL_POWER P3V3_STBY
J 1
(-1550 2175);
DISPLAY 0.489362 (-1550 2175);
PAINT GREEN (-1550 2175);
FORCEPROP 2 LAST CDS_LIB pure_quanta_power
J 0
(-1550 2125);
DISPLAY INVISIBLE (-1550 2125);
FORCEPROP 1 LAST PATH I388
J 0
(-1500 2150);
DISPLAY 0.872340 (-1500 2150);
PAINT AQUA (-1500 2150);
DISPLAY INVISIBLE (-1500 2150);
FORCEADD GND..1
(-350 450);
FORCEPROP 3 LASTPIN (-350 500) SIG_NAME GND\g
J 0
(-340 510);
DISPLAY 0.659574 (-340 510);
PAINT MONO (-340 510);
DISPLAY INVISIBLE (-340 510);
FORCEPROP 1 LAST SIZE 1B
J 0
(-275 400);
DISPLAY 0.851064 (-275 400);
PAINT GREEN (-275 400);
DISPLAY INVISIBLE (-275 400);
FORCEPROP 2 LAST BOM_COST MEM
J 0
(-450 525);
DISPLAY 0.808511 (-450 525);
DISPLAY INVISIBLE (-450 525);
FORCEPROP 2 LAST CDS_LIB pure_quanta_power
J 0
(-350 450);
DISPLAY INVISIBLE (-350 450);
FORCEPROP 1 LAST PATH I389
J 0
(-275 450);
DISPLAY 0.872340 (-275 450);
PAINT AQUA (-275 450);
DISPLAY INVISIBLE (-275 450);
FORCEPROP 1 LAST HDL_POWER GND
J 0
(-350 600);
DISPLAY 0.851064 (-350 600);
PAINT GREEN (-350 600);
DISPLAY INVISIBLE (-350 600);
FORCEADD Q_CAP..2
(-1175 1800);
FORCEPROP 1 LAST LOCATION C1171
J 0
(-1475 1800);
DISPLAY 0.489362 (-1475 1800);
PAINT SKYBLUE (-1475 1800);
FORCEPROP 0 LAST $SEC 1
J 0
(-425 1850);
DISPLAY 0.680851 (-425 1850);
PAINT MONO (-425 1850);
DISPLAY INVISIBLE (-425 1850);
FORCEPROP 0 LAST CDS_SEC 1
J 0
(-425 1850);
DISPLAY 1.021277 (-425 1850);
DISPLAY INVISIBLE (-425 1850);
FORCEPROP 1 LASTPIN (-1275 1800) $PN 1
J 0
(-1285 1815);
DISPLAY 0.489362 (-1285 1815);
PAINT MONO (-1285 1815);
FORCEPROP 1 LASTPIN (-1075 1800) $PN 2
J 0
(-1090 1815);
DISPLAY 0.489362 (-1090 1815);
PAINT MONO (-1090 1815);
FORCEPROP 1 LAST MATERIAL X7R
J 0
(-800 1775);
DISPLAY 0.489362 (-800 1775);
PAINT SKYBLUE (-800 1775);
FORCEPROP 1 LAST TOLERANCE 10%
J 2
(-875 1775);
DISPLAY 0.489362 (-875 1775);
PAINT SKYBLUE (-875 1775);
FORCEPROP 1 LAST VALUE 0.1UF
J 2
(-825 1800);
DISPLAY 0.489362 (-825 1800);
PAINT SKYBLUE (-825 1800);
FORCEPROP 1 LAST PART_NUMBER CH4103K1B08
J 1
(-400 1800);
DISPLAY 0.489362 (-400 1800);
PAINT SKYBLUE (-400 1800);
FORCEPROP 1 LAST VOLTAGE 16V
J 0
(-800 1800);
DISPLAY 0.489362 (-800 1800);
PAINT SKYBLUE (-800 1800);
FORCEPROP 1 LAST PACK_TYPE C0402
J 1
(-650 1800);
DISPLAY 0.489362 (-650 1800);
PAINT SKYBLUE (-650 1800);
FORCEPROP 2 LAST CDS_LIB pure_quanta
J 0
(-1175 1800);
DISPLAY INVISIBLE (-1175 1800);
FORCEPROP 1 LAST PATH I392
J 0
(-1175 2000);
DISPLAY 0.978723 (-1175 2000);
PAINT WHITE (-1175 2000);
DISPLAY INVISIBLE (-1175 2000);
FORCEADD Q_CAP..2
(-1175 1700);
FORCEPROP 1 LAST LOCATION C1172
J 0
(-1475 1700);
DISPLAY 0.489362 (-1475 1700);
PAINT SKYBLUE (-1475 1700);
FORCEPROP 0 LAST $SEC 1
J 0
(-800 1750);
DISPLAY 0.680851 (-800 1750);
PAINT MONO (-800 1750);
DISPLAY INVISIBLE (-800 1750);
FORCEPROP 0 LAST CDS_SEC 1
J 0
(-800 1750);
DISPLAY 1.021277 (-800 1750);
DISPLAY INVISIBLE (-800 1750);
FORCEPROP 1 LASTPIN (-1275 1700) $PN 1
J 0
(-1285 1715);
DISPLAY 0.489362 (-1285 1715);
PAINT MONO (-1285 1715);
FORCEPROP 1 LASTPIN (-1075 1700) $PN 2
J 0
(-1090 1715);
DISPLAY 0.489362 (-1090 1715);
PAINT MONO (-1090 1715);
FORCEPROP 1 LAST VALUE 0.1UF
J 2
(-800 1700);
DISPLAY 0.489362 (-800 1700);
PAINT SKYBLUE (-800 1700);
FORCEPROP 2 LAST CDS_LIB pure_quanta
J 0
(-1175 1700);
DISPLAY INVISIBLE (-1175 1700);
FORCEPROP 1 LAST PATH I393
J 0
(-1175 1900);
DISPLAY 0.978723 (-1175 1900);
PAINT WHITE (-1175 1900);
DISPLAY INVISIBLE (-1175 1900);
FORCEPROP 1 LAST MATERIAL X7R
J 0
(-825 1650);
DISPLAY 0.978723 (-825 1650);
PAINT SKYBLUE (-825 1650);
DISPLAY INVISIBLE (-825 1650);
FORCEPROP 1 LAST TOLERANCE 10%
J 2
(-900 1650);
DISPLAY 0.978723 (-900 1650);
PAINT SKYBLUE (-900 1650);
DISPLAY INVISIBLE (-900 1650);
FORCEPROP 1 LAST PART_NUMBER CH4103K1B08
J 1
(-425 1700);
DISPLAY 0.978723 (-425 1700);
PAINT SKYBLUE (-425 1700);
DISPLAY INVISIBLE (-425 1700);
FORCEPROP 1 LAST VOLTAGE 16V
J 0
(-650 1650);
DISPLAY 0.978723 (-650 1650);
PAINT SKYBLUE (-650 1650);
DISPLAY INVISIBLE (-650 1650);
FORCEPROP 1 LAST PACK_TYPE C0402
J 1
(-325 1650);
DISPLAY 0.978723 (-325 1650);
PAINT SKYBLUE (-325 1650);
DISPLAY INVISIBLE (-325 1650);
FORCEADD Q_CAP..2
(-1175 1600);
FORCEPROP 1 LAST LOCATION C1173
J 0
(-1475 1600);
DISPLAY 0.489362 (-1475 1600);
PAINT SKYBLUE (-1475 1600);
FORCEPROP 0 LAST $SEC 1
J 0
(-425 1650);
DISPLAY 0.680851 (-425 1650);
PAINT MONO (-425 1650);
DISPLAY INVISIBLE (-425 1650);
FORCEPROP 0 LAST CDS_SEC 1
J 0
(-425 1650);
DISPLAY 1.021277 (-425 1650);
DISPLAY INVISIBLE (-425 1650);
FORCEPROP 1 LASTPIN (-1275 1600) $PN 1
J 0
(-1285 1615);
DISPLAY 0.489362 (-1285 1615);
PAINT MONO (-1285 1615);
FORCEPROP 1 LASTPIN (-1075 1600) $PN 2
J 0
(-1090 1615);
DISPLAY 0.489362 (-1090 1615);
PAINT MONO (-1090 1615);
FORCEPROP 1 LAST VALUE 0.1UF
J 2
(-800 1600);
DISPLAY 0.489362 (-800 1600);
PAINT SKYBLUE (-800 1600);
FORCEPROP 2 LAST CDS_LIB pure_quanta
J 0
(-1175 1600);
DISPLAY INVISIBLE (-1175 1600);
FORCEPROP 1 LAST PATH I394
J 0
(-1175 1800);
DISPLAY 0.978723 (-1175 1800);
PAINT WHITE (-1175 1800);
DISPLAY INVISIBLE (-1175 1800);
FORCEPROP 1 LAST MATERIAL X7R
J 0
(-975 1550);
DISPLAY 0.489362 (-975 1550);
PAINT SKYBLUE (-975 1550);
DISPLAY INVISIBLE (-975 1550);
FORCEPROP 1 LAST TOLERANCE 10%
J 2
(-900 1575);
DISPLAY 0.489362 (-900 1575);
PAINT SKYBLUE (-900 1575);
DISPLAY INVISIBLE (-900 1575);
FORCEPROP 1 LAST PART_NUMBER CH4103K1B08
J 1
(-550 1600);
DISPLAY 0.489362 (-550 1600);
PAINT SKYBLUE (-550 1600);
DISPLAY INVISIBLE (-550 1600);
FORCEPROP 1 LAST VOLTAGE 16V
J 0
(-775 1575);
DISPLAY 0.489362 (-775 1575);
PAINT SKYBLUE (-775 1575);
DISPLAY INVISIBLE (-775 1575);
FORCEPROP 1 LAST PACK_TYPE C0402
J 1
(-725 1550);
DISPLAY 0.489362 (-725 1550);
PAINT SKYBLUE (-725 1550);
DISPLAY INVISIBLE (-725 1550);
FORCEADD Q_CAP..2
(-1175 1500);
FORCEPROP 1 LAST LOCATION C1174
J 0
(-1475 1500);
DISPLAY 0.489362 (-1475 1500);
PAINT SKYBLUE (-1475 1500);
FORCEPROP 0 LAST $SEC 1
J 0
(-800 1550);
DISPLAY 0.680851 (-800 1550);
PAINT MONO (-800 1550);
DISPLAY INVISIBLE (-800 1550);
FORCEPROP 0 LAST CDS_SEC 1
J 0
(-800 1550);
DISPLAY 1.021277 (-800 1550);
DISPLAY INVISIBLE (-800 1550);
FORCEPROP 1 LASTPIN (-1275 1500) $PN 1
J 0
(-1285 1515);
DISPLAY 0.489362 (-1285 1515);
PAINT MONO (-1285 1515);
FORCEPROP 1 LASTPIN (-1075 1500) $PN 2
J 0
(-1090 1515);
DISPLAY 0.489362 (-1090 1515);
PAINT MONO (-1090 1515);
FORCEPROP 1 LAST VALUE 0.1UF
J 2
(-800 1500);
DISPLAY 0.489362 (-800 1500);
PAINT SKYBLUE (-800 1500);
FORCEPROP 2 LAST CDS_LIB pure_quanta
J 0
(-1175 1500);
DISPLAY INVISIBLE (-1175 1500);
FORCEPROP 1 LAST PATH I395
J 0
(-1175 1700);
DISPLAY 0.978723 (-1175 1700);
PAINT WHITE (-1175 1700);
DISPLAY INVISIBLE (-1175 1700);
FORCEPROP 1 LAST MATERIAL X7R
J 0
(-825 1450);
DISPLAY 0.978723 (-825 1450);
PAINT SKYBLUE (-825 1450);
DISPLAY INVISIBLE (-825 1450);
FORCEPROP 1 LAST TOLERANCE 10%
J 2
(-900 1450);
DISPLAY 0.978723 (-900 1450);
PAINT SKYBLUE (-900 1450);
DISPLAY INVISIBLE (-900 1450);
FORCEPROP 1 LAST PART_NUMBER CH4103K1B08
J 1
(-425 1500);
DISPLAY 0.978723 (-425 1500);
PAINT SKYBLUE (-425 1500);
DISPLAY INVISIBLE (-425 1500);
FORCEPROP 1 LAST VOLTAGE 16V
J 0
(-650 1450);
DISPLAY 0.978723 (-650 1450);
PAINT SKYBLUE (-650 1450);
DISPLAY INVISIBLE (-650 1450);
FORCEPROP 1 LAST PACK_TYPE C0402
J 1
(-325 1450);
DISPLAY 0.978723 (-325 1450);
PAINT SKYBLUE (-325 1450);
DISPLAY INVISIBLE (-325 1450);
FORCEADD Q_CAP..2
(-1175 1400);
FORCEPROP 1 LAST LOCATION C1175
J 0
(-1475 1400);
DISPLAY 0.489362 (-1475 1400);
PAINT SKYBLUE (-1475 1400);
FORCEPROP 0 LAST $SEC 1
J 0
(-800 1450);
DISPLAY 0.680851 (-800 1450);
PAINT MONO (-800 1450);
DISPLAY INVISIBLE (-800 1450);
FORCEPROP 0 LAST CDS_SEC 1
J 0
(-800 1450);
DISPLAY 1.021277 (-800 1450);
DISPLAY INVISIBLE (-800 1450);
FORCEPROP 1 LASTPIN (-1275 1400) $PN 1
J 0
(-1285 1415);
DISPLAY 0.489362 (-1285 1415);
PAINT MONO (-1285 1415);
FORCEPROP 1 LASTPIN (-1075 1400) $PN 2
J 0
(-1090 1415);
DISPLAY 0.489362 (-1090 1415);
PAINT MONO (-1090 1415);
FORCEPROP 1 LAST VALUE 0.1UF
J 2
(-800 1400);
DISPLAY 0.489362 (-800 1400);
PAINT SKYBLUE (-800 1400);
FORCEPROP 2 LAST CDS_LIB pure_quanta
J 0
(-1175 1400);
DISPLAY INVISIBLE (-1175 1400);
FORCEPROP 1 LAST PATH I396
J 0
(-1175 1600);
DISPLAY 0.978723 (-1175 1600);
PAINT WHITE (-1175 1600);
DISPLAY INVISIBLE (-1175 1600);
FORCEPROP 1 LAST MATERIAL X7R
J 0
(-825 1350);
DISPLAY 0.978723 (-825 1350);
PAINT SKYBLUE (-825 1350);
DISPLAY INVISIBLE (-825 1350);
FORCEPROP 1 LAST TOLERANCE 10%
J 2
(-900 1350);
DISPLAY 0.978723 (-900 1350);
PAINT SKYBLUE (-900 1350);
DISPLAY INVISIBLE (-900 1350);
FORCEPROP 1 LAST PART_NUMBER CH4103K1B08
J 1
(-425 1400);
DISPLAY 0.978723 (-425 1400);
PAINT SKYBLUE (-425 1400);
DISPLAY INVISIBLE (-425 1400);
FORCEPROP 1 LAST VOLTAGE 16V
J 0
(-650 1350);
DISPLAY 0.978723 (-650 1350);
PAINT SKYBLUE (-650 1350);
DISPLAY INVISIBLE (-650 1350);
FORCEPROP 1 LAST PACK_TYPE C0402
J 1
(-325 1350);
DISPLAY 0.978723 (-325 1350);
PAINT SKYBLUE (-325 1350);
DISPLAY INVISIBLE (-325 1350);
FORCEADD Q_CAP..2
(-1175 1300);
FORCEPROP 1 LAST LOCATION C1176
J 0
(-1475 1300);
DISPLAY 0.489362 (-1475 1300);
PAINT SKYBLUE (-1475 1300);
FORCEPROP 0 LAST $SEC 1
J 0
(-800 1350);
DISPLAY 0.680851 (-800 1350);
PAINT MONO (-800 1350);
DISPLAY INVISIBLE (-800 1350);
FORCEPROP 0 LAST CDS_SEC 1
J 0
(-800 1350);
DISPLAY 1.021277 (-800 1350);
DISPLAY INVISIBLE (-800 1350);
FORCEPROP 1 LASTPIN (-1275 1300) $PN 1
J 0
(-1285 1315);
DISPLAY 0.489362 (-1285 1315);
PAINT MONO (-1285 1315);
FORCEPROP 1 LASTPIN (-1075 1300) $PN 2
J 0
(-1090 1315);
DISPLAY 0.489362 (-1090 1315);
PAINT MONO (-1090 1315);
FORCEPROP 1 LAST VALUE 0.1UF
J 2
(-800 1300);
DISPLAY 0.489362 (-800 1300);
PAINT SKYBLUE (-800 1300);
FORCEPROP 2 LAST CDS_LIB pure_quanta
J 0
(-1175 1300);
DISPLAY INVISIBLE (-1175 1300);
FORCEPROP 1 LAST PATH I397
J 0
(-1175 1500);
DISPLAY 0.978723 (-1175 1500);
PAINT WHITE (-1175 1500);
DISPLAY INVISIBLE (-1175 1500);
FORCEPROP 1 LAST MATERIAL X7R
J 0
(-825 1250);
DISPLAY 0.978723 (-825 1250);
PAINT SKYBLUE (-825 1250);
DISPLAY INVISIBLE (-825 1250);
FORCEPROP 1 LAST TOLERANCE 10%
J 2
(-900 1250);
DISPLAY 0.978723 (-900 1250);
PAINT SKYBLUE (-900 1250);
DISPLAY INVISIBLE (-900 1250);
FORCEPROP 1 LAST PART_NUMBER CH4103K1B08
J 1
(-425 1300);
DISPLAY 0.978723 (-425 1300);
PAINT SKYBLUE (-425 1300);
DISPLAY INVISIBLE (-425 1300);
FORCEPROP 1 LAST VOLTAGE 16V
J 0
(-650 1250);
DISPLAY 0.978723 (-650 1250);
PAINT SKYBLUE (-650 1250);
DISPLAY INVISIBLE (-650 1250);
FORCEPROP 1 LAST PACK_TYPE C0402
J 1
(-325 1250);
DISPLAY 0.978723 (-325 1250);
PAINT SKYBLUE (-325 1250);
DISPLAY INVISIBLE (-325 1250);
FORCEADD Q_CAP..2
(-1175 1200);
FORCEPROP 1 LAST LOCATION C355
J 0
(-1475 1200);
DISPLAY 0.489362 (-1475 1200);
PAINT SKYBLUE (-1475 1200);
FORCEPROP 2 LAST $SEC 1
J 0
(-1175 1450);
DISPLAY 0.680851 (-1175 1450);
PAINT MONO (-1175 1450);
DISPLAY INVISIBLE (-1175 1450);
FORCEPROP 2 LAST CDS_SEC 1
J 0
(-1175 1450);
DISPLAY 1.021277 (-1175 1450);
DISPLAY INVISIBLE (-1175 1450);
FORCEPROP 1 LASTPIN (-1275 1200) $PN 1
J 0
(-1285 1215);
DISPLAY 0.489362 (-1285 1215);
PAINT MONO (-1285 1215);
FORCEPROP 1 LASTPIN (-1075 1200) $PN 2
J 0
(-1090 1215);
DISPLAY 0.489362 (-1090 1215);
PAINT MONO (-1090 1215);
FORCEPROP 1 LAST VALUE 0.1UF
J 2
(-800 1200);
DISPLAY 0.489362 (-800 1200);
PAINT SKYBLUE (-800 1200);
FORCEPROP 2 LAST CDS_LIB pure_quanta
J 0
(-1175 1200);
DISPLAY INVISIBLE (-1175 1200);
FORCEPROP 1 LAST PATH I398
J 0
(-1175 1400);
DISPLAY 0.978723 (-1175 1400);
PAINT WHITE (-1175 1400);
DISPLAY INVISIBLE (-1175 1400);
FORCEPROP 1 LAST MATERIAL X7R
J 0
(-825 1150);
DISPLAY 0.978723 (-825 1150);
PAINT SKYBLUE (-825 1150);
DISPLAY INVISIBLE (-825 1150);
FORCEPROP 1 LAST TOLERANCE 10%
J 2
(-900 1150);
DISPLAY 0.978723 (-900 1150);
PAINT SKYBLUE (-900 1150);
DISPLAY INVISIBLE (-900 1150);
FORCEPROP 1 LAST PART_NUMBER CH4103K1B08
J 1
(-425 1200);
DISPLAY 0.978723 (-425 1200);
PAINT SKYBLUE (-425 1200);
DISPLAY INVISIBLE (-425 1200);
FORCEPROP 1 LAST VOLTAGE 16V
J 0
(-650 1150);
DISPLAY 0.978723 (-650 1150);
PAINT SKYBLUE (-650 1150);
DISPLAY INVISIBLE (-650 1150);
FORCEPROP 1 LAST PACK_TYPE C0402
J 1
(-325 1150);
DISPLAY 0.978723 (-325 1150);
PAINT SKYBLUE (-325 1150);
DISPLAY INVISIBLE (-325 1150);
FORCEADD Q_CAP..2
(-1175 1100);
FORCEPROP 1 LAST LOCATION C356
J 0
(-1475 1100);
DISPLAY 0.489362 (-1475 1100);
PAINT SKYBLUE (-1475 1100);
FORCEPROP 2 LAST $SEC 1
J 0
(-1175 1350);
DISPLAY 0.680851 (-1175 1350);
PAINT MONO (-1175 1350);
DISPLAY INVISIBLE (-1175 1350);
FORCEPROP 2 LAST CDS_SEC 1
J 0
(-1175 1350);
DISPLAY 1.021277 (-1175 1350);
DISPLAY INVISIBLE (-1175 1350);
FORCEPROP 1 LASTPIN (-1275 1100) $PN 1
J 0
(-1285 1115);
DISPLAY 0.489362 (-1285 1115);
PAINT MONO (-1285 1115);
FORCEPROP 1 LASTPIN (-1075 1100) $PN 2
J 0
(-1090 1115);
DISPLAY 0.489362 (-1090 1115);
PAINT MONO (-1090 1115);
FORCEPROP 1 LAST VALUE 0.1UF
J 2
(-800 1100);
DISPLAY 0.489362 (-800 1100);
PAINT SKYBLUE (-800 1100);
FORCEPROP 2 LAST CDS_LIB pure_quanta
J 0
(-1175 1100);
DISPLAY INVISIBLE (-1175 1100);
FORCEPROP 1 LAST PATH I399
J 0
(-1175 1300);
DISPLAY 0.978723 (-1175 1300);
PAINT WHITE (-1175 1300);
DISPLAY INVISIBLE (-1175 1300);
FORCEPROP 1 LAST MATERIAL X7R
J 0
(-825 1050);
DISPLAY 0.978723 (-825 1050);
PAINT SKYBLUE (-825 1050);
DISPLAY INVISIBLE (-825 1050);
FORCEPROP 1 LAST TOLERANCE 10%
J 2
(-900 1050);
DISPLAY 0.978723 (-900 1050);
PAINT SKYBLUE (-900 1050);
DISPLAY INVISIBLE (-900 1050);
FORCEPROP 1 LAST PART_NUMBER CH4103K1B08
J 1
(-425 1100);
DISPLAY 0.978723 (-425 1100);
PAINT SKYBLUE (-425 1100);
DISPLAY INVISIBLE (-425 1100);
FORCEPROP 1 LAST VOLTAGE 16V
J 0
(-650 1050);
DISPLAY 0.978723 (-650 1050);
PAINT SKYBLUE (-650 1050);
DISPLAY INVISIBLE (-650 1050);
FORCEPROP 1 LAST PACK_TYPE C0402
J 1
(-325 1050);
DISPLAY 0.978723 (-325 1050);
PAINT SKYBLUE (-325 1050);
DISPLAY INVISIBLE (-325 1050);
FORCEADD Q_CAP..2
(-1175 1000);
FORCEPROP 1 LAST LOCATION C357
J 0
(-1475 1000);
DISPLAY 0.489362 (-1475 1000);
PAINT SKYBLUE (-1475 1000);
FORCEPROP 2 LAST $SEC 1
J 0
(-1175 1250);
DISPLAY 0.680851 (-1175 1250);
PAINT MONO (-1175 1250);
DISPLAY INVISIBLE (-1175 1250);
FORCEPROP 2 LAST CDS_SEC 1
J 0
(-1175 1250);
DISPLAY 1.021277 (-1175 1250);
DISPLAY INVISIBLE (-1175 1250);
FORCEPROP 1 LASTPIN (-1275 1000) $PN 1
J 0
(-1285 1015);
DISPLAY 0.489362 (-1285 1015);
PAINT MONO (-1285 1015);
FORCEPROP 1 LASTPIN (-1075 1000) $PN 2
J 0
(-1090 1015);
DISPLAY 0.489362 (-1090 1015);
PAINT MONO (-1090 1015);
FORCEPROP 1 LAST VALUE 0.1UF
J 2
(-800 1000);
DISPLAY 0.489362 (-800 1000);
PAINT SKYBLUE (-800 1000);
FORCEPROP 2 LAST CDS_LIB pure_quanta
J 0
(-1175 1000);
DISPLAY INVISIBLE (-1175 1000);
FORCEPROP 1 LAST PATH I400
J 0
(-1175 1200);
DISPLAY 0.978723 (-1175 1200);
PAINT WHITE (-1175 1200);
DISPLAY INVISIBLE (-1175 1200);
FORCEPROP 1 LAST MATERIAL X7R
J 0
(-825 950);
DISPLAY 0.978723 (-825 950);
PAINT SKYBLUE (-825 950);
DISPLAY INVISIBLE (-825 950);
FORCEPROP 1 LAST TOLERANCE 10%
J 2
(-900 950);
DISPLAY 0.978723 (-900 950);
PAINT SKYBLUE (-900 950);
DISPLAY INVISIBLE (-900 950);
FORCEPROP 1 LAST PART_NUMBER CH4103K1B08
J 1
(-425 1000);
DISPLAY 0.978723 (-425 1000);
PAINT SKYBLUE (-425 1000);
DISPLAY INVISIBLE (-425 1000);
FORCEPROP 1 LAST VOLTAGE 16V
J 0
(-650 950);
DISPLAY 0.978723 (-650 950);
PAINT SKYBLUE (-650 950);
DISPLAY INVISIBLE (-650 950);
FORCEPROP 1 LAST PACK_TYPE C0402
J 1
(-325 950);
DISPLAY 0.978723 (-325 950);
PAINT SKYBLUE (-325 950);
DISPLAY INVISIBLE (-325 950);
FORCEADD Q_CAP..2
(-1175 900);
FORCEPROP 1 LAST LOCATION C358
J 0
(-1475 900);
DISPLAY 0.489362 (-1475 900);
PAINT SKYBLUE (-1475 900);
FORCEPROP 2 LAST $SEC 1
J 0
(-1175 1150);
DISPLAY 0.680851 (-1175 1150);
PAINT MONO (-1175 1150);
DISPLAY INVISIBLE (-1175 1150);
FORCEPROP 2 LAST CDS_SEC 1
J 0
(-1175 1150);
DISPLAY 1.021277 (-1175 1150);
DISPLAY INVISIBLE (-1175 1150);
FORCEPROP 1 LASTPIN (-1275 900) $PN 1
J 0
(-1285 915);
DISPLAY 0.489362 (-1285 915);
PAINT MONO (-1285 915);
FORCEPROP 1 LASTPIN (-1075 900) $PN 2
J 0
(-1090 915);
DISPLAY 0.489362 (-1090 915);
PAINT MONO (-1090 915);
FORCEPROP 1 LAST VALUE 0.1UF
J 2
(-800 900);
DISPLAY 0.489362 (-800 900);
PAINT SKYBLUE (-800 900);
FORCEPROP 2 LAST CDS_LIB pure_quanta
J 0
(-1175 900);
DISPLAY INVISIBLE (-1175 900);
FORCEPROP 1 LAST PATH I401
J 0
(-1175 1100);
DISPLAY 0.978723 (-1175 1100);
PAINT WHITE (-1175 1100);
DISPLAY INVISIBLE (-1175 1100);
FORCEPROP 1 LAST MATERIAL X7R
J 0
(-825 850);
DISPLAY 0.978723 (-825 850);
PAINT SKYBLUE (-825 850);
DISPLAY INVISIBLE (-825 850);
FORCEPROP 1 LAST TOLERANCE 10%
J 2
(-900 850);
DISPLAY 0.978723 (-900 850);
PAINT SKYBLUE (-900 850);
DISPLAY INVISIBLE (-900 850);
FORCEPROP 1 LAST PART_NUMBER CH4103K1B08
J 1
(-425 900);
DISPLAY 0.978723 (-425 900);
PAINT SKYBLUE (-425 900);
DISPLAY INVISIBLE (-425 900);
FORCEPROP 1 LAST VOLTAGE 16V
J 0
(-650 850);
DISPLAY 0.978723 (-650 850);
PAINT SKYBLUE (-650 850);
DISPLAY INVISIBLE (-650 850);
FORCEPROP 1 LAST PACK_TYPE C0402
J 1
(-325 850);
DISPLAY 0.978723 (-325 850);
PAINT SKYBLUE (-325 850);
DISPLAY INVISIBLE (-325 850);
FORCEADD Q_CAP..2
(-1175 800);
FORCEPROP 1 LAST LOCATION C359
J 0
(-1475 800);
DISPLAY 0.489362 (-1475 800);
PAINT SKYBLUE (-1475 800);
FORCEPROP 2 LAST $SEC 1
J 0
(-1175 1050);
DISPLAY 0.680851 (-1175 1050);
PAINT MONO (-1175 1050);
DISPLAY INVISIBLE (-1175 1050);
FORCEPROP 2 LAST CDS_SEC 1
J 0
(-1175 1050);
DISPLAY 1.021277 (-1175 1050);
DISPLAY INVISIBLE (-1175 1050);
FORCEPROP 1 LASTPIN (-1275 800) $PN 1
J 0
(-1285 815);
DISPLAY 0.489362 (-1285 815);
PAINT MONO (-1285 815);
FORCEPROP 1 LASTPIN (-1075 800) $PN 2
J 0
(-1090 815);
DISPLAY 0.489362 (-1090 815);
PAINT MONO (-1090 815);
FORCEPROP 1 LAST VALUE 0.1UF
J 2
(-800 800);
DISPLAY 0.489362 (-800 800);
PAINT SKYBLUE (-800 800);
FORCEPROP 2 LAST CDS_LIB pure_quanta
J 0
(-1175 800);
DISPLAY INVISIBLE (-1175 800);
FORCEPROP 1 LAST PATH I402
J 0
(-1175 1000);
DISPLAY 0.978723 (-1175 1000);
PAINT WHITE (-1175 1000);
DISPLAY INVISIBLE (-1175 1000);
FORCEPROP 1 LAST MATERIAL X7R
J 0
(-825 750);
DISPLAY 0.978723 (-825 750);
PAINT SKYBLUE (-825 750);
DISPLAY INVISIBLE (-825 750);
FORCEPROP 1 LAST TOLERANCE 10%
J 2
(-900 750);
DISPLAY 0.978723 (-900 750);
PAINT SKYBLUE (-900 750);
DISPLAY INVISIBLE (-900 750);
FORCEPROP 1 LAST PART_NUMBER CH4103K1B08
J 1
(-425 800);
DISPLAY 0.978723 (-425 800);
PAINT SKYBLUE (-425 800);
DISPLAY INVISIBLE (-425 800);
FORCEPROP 1 LAST VOLTAGE 16V
J 0
(-650 750);
DISPLAY 0.978723 (-650 750);
PAINT SKYBLUE (-650 750);
DISPLAY INVISIBLE (-650 750);
FORCEPROP 1 LAST PACK_TYPE C0402
J 1
(-325 750);
DISPLAY 0.978723 (-325 750);
PAINT SKYBLUE (-325 750);
DISPLAY INVISIBLE (-325 750);
FORCEADD Q_CAP..2
(-1175 700);
FORCEPROP 1 LAST LOCATION C360
J 0
(-1475 700);
DISPLAY 0.489362 (-1475 700);
PAINT SKYBLUE (-1475 700);
FORCEPROP 2 LAST $SEC 1
J 0
(-1175 950);
DISPLAY 0.680851 (-1175 950);
PAINT MONO (-1175 950);
DISPLAY INVISIBLE (-1175 950);
FORCEPROP 2 LAST CDS_SEC 1
J 0
(-1175 950);
DISPLAY 1.021277 (-1175 950);
DISPLAY INVISIBLE (-1175 950);
FORCEPROP 1 LASTPIN (-1275 700) $PN 1
J 0
(-1285 715);
DISPLAY 0.489362 (-1285 715);
PAINT MONO (-1285 715);
FORCEPROP 1 LASTPIN (-1075 700) $PN 2
J 0
(-1090 715);
DISPLAY 0.489362 (-1090 715);
PAINT MONO (-1090 715);
FORCEPROP 1 LAST VALUE 0.1UF
J 2
(-800 700);
DISPLAY 0.489362 (-800 700);
PAINT SKYBLUE (-800 700);
FORCEPROP 2 LAST CDS_LIB pure_quanta
J 0
(-1175 700);
DISPLAY INVISIBLE (-1175 700);
FORCEPROP 1 LAST PATH I403
J 0
(-1175 900);
DISPLAY 0.978723 (-1175 900);
PAINT WHITE (-1175 900);
DISPLAY INVISIBLE (-1175 900);
FORCEPROP 1 LAST MATERIAL X7R
J 0
(-825 650);
DISPLAY 0.978723 (-825 650);
PAINT SKYBLUE (-825 650);
DISPLAY INVISIBLE (-825 650);
FORCEPROP 1 LAST TOLERANCE 10%
J 2
(-900 650);
DISPLAY 0.978723 (-900 650);
PAINT SKYBLUE (-900 650);
DISPLAY INVISIBLE (-900 650);
FORCEPROP 1 LAST PART_NUMBER CH4103K1B08
J 1
(-425 700);
DISPLAY 0.978723 (-425 700);
PAINT SKYBLUE (-425 700);
DISPLAY INVISIBLE (-425 700);
FORCEPROP 1 LAST VOLTAGE 16V
J 0
(-650 650);
DISPLAY 0.978723 (-650 650);
PAINT SKYBLUE (-650 650);
DISPLAY INVISIBLE (-650 650);
FORCEPROP 1 LAST PACK_TYPE C0402
J 1
(-325 650);
DISPLAY 0.978723 (-325 650);
PAINT SKYBLUE (-325 650);
DISPLAY INVISIBLE (-325 650);
FORCEADD Q_CAP..2
(-1175 600);
FORCEPROP 1 LAST LOCATION C361
J 0
(-1475 600);
DISPLAY 0.489362 (-1475 600);
PAINT SKYBLUE (-1475 600);
FORCEPROP 2 LAST $SEC 1
J 0
(-1175 850);
DISPLAY 0.680851 (-1175 850);
PAINT MONO (-1175 850);
DISPLAY INVISIBLE (-1175 850);
FORCEPROP 2 LAST CDS_SEC 1
J 0
(-1175 850);
DISPLAY 1.021277 (-1175 850);
DISPLAY INVISIBLE (-1175 850);
FORCEPROP 1 LASTPIN (-1275 600) $PN 1
J 0
(-1285 615);
DISPLAY 0.489362 (-1285 615);
PAINT MONO (-1285 615);
FORCEPROP 1 LASTPIN (-1075 600) $PN 2
J 0
(-1090 615);
DISPLAY 0.489362 (-1090 615);
PAINT MONO (-1090 615);
FORCEPROP 1 LAST VALUE 0.1UF
J 2
(-800 600);
DISPLAY 0.489362 (-800 600);
PAINT SKYBLUE (-800 600);
FORCEPROP 2 LAST CDS_LIB pure_quanta
J 0
(-1175 600);
DISPLAY INVISIBLE (-1175 600);
FORCEPROP 1 LAST PATH I404
J 0
(-1175 800);
DISPLAY 0.978723 (-1175 800);
PAINT WHITE (-1175 800);
DISPLAY INVISIBLE (-1175 800);
FORCEPROP 1 LAST MATERIAL X7R
J 0
(-825 550);
DISPLAY 0.978723 (-825 550);
PAINT SKYBLUE (-825 550);
DISPLAY INVISIBLE (-825 550);
FORCEPROP 1 LAST TOLERANCE 10%
J 2
(-900 550);
DISPLAY 0.978723 (-900 550);
PAINT SKYBLUE (-900 550);
DISPLAY INVISIBLE (-900 550);
FORCEPROP 1 LAST PART_NUMBER CH4103K1B08
J 1
(-425 600);
DISPLAY 0.978723 (-425 600);
PAINT SKYBLUE (-425 600);
DISPLAY INVISIBLE (-425 600);
FORCEPROP 1 LAST VOLTAGE 16V
J 0
(-650 550);
DISPLAY 0.978723 (-650 550);
PAINT SKYBLUE (-650 550);
DISPLAY INVISIBLE (-650 550);
FORCEPROP 1 LAST PACK_TYPE C0402
J 1
(-325 550);
DISPLAY 0.978723 (-325 550);
PAINT SKYBLUE (-325 550);
DISPLAY INVISIBLE (-325 550);
FORCEADD Q_CAP..2
(-1175 500);
FORCEPROP 1 LAST LOCATION C362
J 0
(-1475 500);
DISPLAY 0.489362 (-1475 500);
PAINT SKYBLUE (-1475 500);
FORCEPROP 2 LAST $SEC 1
J 0
(-1175 750);
DISPLAY 0.680851 (-1175 750);
PAINT MONO (-1175 750);
DISPLAY INVISIBLE (-1175 750);
FORCEPROP 2 LAST CDS_SEC 1
J 0
(-1175 750);
DISPLAY 1.021277 (-1175 750);
DISPLAY INVISIBLE (-1175 750);
FORCEPROP 1 LASTPIN (-1275 500) $PN 1
J 0
(-1285 515);
DISPLAY 0.489362 (-1285 515);
PAINT MONO (-1285 515);
FORCEPROP 1 LASTPIN (-1075 500) $PN 2
J 0
(-1090 515);
DISPLAY 0.489362 (-1090 515);
PAINT MONO (-1090 515);
FORCEPROP 1 LAST VALUE 0.1UF
J 2
(-800 500);
DISPLAY 0.489362 (-800 500);
PAINT SKYBLUE (-800 500);
FORCEPROP 2 LAST CDS_LIB pure_quanta
J 0
(-1175 500);
DISPLAY INVISIBLE (-1175 500);
FORCEPROP 1 LAST PATH I405
J 0
(-1175 700);
DISPLAY 0.978723 (-1175 700);
PAINT WHITE (-1175 700);
DISPLAY INVISIBLE (-1175 700);
FORCEPROP 1 LAST MATERIAL X7R
J 0
(-825 450);
DISPLAY 0.978723 (-825 450);
PAINT SKYBLUE (-825 450);
DISPLAY INVISIBLE (-825 450);
FORCEPROP 1 LAST TOLERANCE 10%
J 2
(-900 450);
DISPLAY 0.978723 (-900 450);
PAINT SKYBLUE (-900 450);
DISPLAY INVISIBLE (-900 450);
FORCEPROP 1 LAST PART_NUMBER CH4103K1B08
J 1
(-425 500);
DISPLAY 0.978723 (-425 500);
PAINT SKYBLUE (-425 500);
DISPLAY INVISIBLE (-425 500);
FORCEPROP 1 LAST VOLTAGE 16V
J 0
(-650 450);
DISPLAY 0.978723 (-650 450);
PAINT SKYBLUE (-650 450);
DISPLAY INVISIBLE (-650 450);
FORCEPROP 1 LAST PACK_TYPE C0402
J 1
(-325 450);
DISPLAY 0.978723 (-325 450);
PAINT SKYBLUE (-325 450);
DISPLAY INVISIBLE (-325 450);
FORCEADD GND..1
(-2075 650);
FORCEPROP 3 LASTPIN (-2075 700) SIG_NAME GND\g
J 0
(-2065 710);
DISPLAY 0.659574 (-2065 710);
PAINT MONO (-2065 710);
DISPLAY INVISIBLE (-2065 710);
FORCEPROP 2 LAST BOM_COST MEM
J 0
(-2175 725);
DISPLAY 0.808511 (-2175 725);
DISPLAY INVISIBLE (-2175 725);
FORCEPROP 1 LAST SIZE 1B
J 0
(-2000 600);
DISPLAY 0.851064 (-2000 600);
PAINT GREEN (-2000 600);
DISPLAY INVISIBLE (-2000 600);
FORCEPROP 2 LAST CDS_LIB pure_quanta_power
J 0
(-2075 650);
DISPLAY INVISIBLE (-2075 650);
FORCEPROP 1 LAST PATH I406
J 0
(-2000 650);
DISPLAY 0.872340 (-2000 650);
PAINT AQUA (-2000 650);
DISPLAY INVISIBLE (-2000 650);
FORCEPROP 1 LAST HDL_POWER GND
J 0
(-2075 800);
DISPLAY 0.851064 (-2075 800);
PAINT GREEN (-2075 800);
DISPLAY INVISIBLE (-2075 800);
FORCEADD Q_CAP..2
(-3425 1950);
FORCEPROP 1 LAST LOCATION C1126
J 0
(-3725 1950);
DISPLAY 0.489362 (-3725 1950);
PAINT SKYBLUE (-3725 1950);
FORCEPROP 0 LAST $SEC 1
J 0
(-2675 2000);
DISPLAY 0.680851 (-2675 2000);
PAINT MONO (-2675 2000);
DISPLAY INVISIBLE (-2675 2000);
FORCEPROP 0 LAST CDS_SEC 1
J 0
(-2675 2000);
DISPLAY 1.021277 (-2675 2000);
DISPLAY INVISIBLE (-2675 2000);
FORCEPROP 1 LASTPIN (-3525 1950) $PN 1
J 0
(-3535 1965);
DISPLAY 0.489362 (-3535 1965);
PAINT MONO (-3535 1965);
FORCEPROP 1 LASTPIN (-3325 1950) $PN 2
J 0
(-3340 1965);
DISPLAY 0.489362 (-3340 1965);
PAINT MONO (-3340 1965);
FORCEPROP 1 LAST MATERIAL X7R
J 0
(-2975 1950);
DISPLAY 0.489362 (-2975 1950);
PAINT SKYBLUE (-2975 1950);
FORCEPROP 1 LAST TOLERANCE 10%
J 2
(-2900 1925);
DISPLAY 0.489362 (-2900 1925);
PAINT SKYBLUE (-2900 1925);
FORCEPROP 1 LAST VALUE 0.1UF
J 2
(-3050 1950);
DISPLAY 0.489362 (-3050 1950);
PAINT SKYBLUE (-3050 1950);
FORCEPROP 1 LAST PART_NUMBER CH4103K1B08
J 1
(-2725 1950);
DISPLAY 0.489362 (-2725 1950);
PAINT SKYBLUE (-2725 1950);
FORCEPROP 1 LAST VOLTAGE 16V
J 0
(-2850 1925);
DISPLAY 0.489362 (-2850 1925);
PAINT SKYBLUE (-2850 1925);
FORCEPROP 1 LAST PACK_TYPE C0402
J 1
(-2675 1925);
DISPLAY 0.489362 (-2675 1925);
PAINT SKYBLUE (-2675 1925);
FORCEPROP 2 LAST CDS_LIB pure_quanta
J 0
(-3425 1950);
DISPLAY INVISIBLE (-3425 1950);
FORCEPROP 1 LAST PATH I407
J 0
(-3425 2150);
DISPLAY 0.978723 (-3425 2150);
PAINT WHITE (-3425 2150);
DISPLAY INVISIBLE (-3425 2150);
FORCEADD Q_CAP..2
(-3425 1750);
FORCEPROP 1 LAST LOCATION C1128
J 0
(-3725 1750);
DISPLAY 0.489362 (-3725 1750);
PAINT SKYBLUE (-3725 1750);
FORCEPROP 0 LAST $SEC 1
J 0
(-3050 1800);
DISPLAY 0.680851 (-3050 1800);
PAINT MONO (-3050 1800);
DISPLAY INVISIBLE (-3050 1800);
FORCEPROP 0 LAST CDS_SEC 1
J 0
(-3050 1800);
DISPLAY 1.021277 (-3050 1800);
DISPLAY INVISIBLE (-3050 1800);
FORCEPROP 1 LASTPIN (-3525 1750) $PN 1
J 0
(-3535 1765);
DISPLAY 0.489362 (-3535 1765);
PAINT MONO (-3535 1765);
FORCEPROP 1 LASTPIN (-3325 1750) $PN 2
J 0
(-3340 1765);
DISPLAY 0.489362 (-3340 1765);
PAINT MONO (-3340 1765);
FORCEPROP 1 LAST VALUE 0.1UF
J 2
(-3050 1750);
DISPLAY 0.489362 (-3050 1750);
PAINT SKYBLUE (-3050 1750);
FORCEPROP 2 LAST CDS_LIB pure_quanta
J 0
(-3425 1750);
DISPLAY INVISIBLE (-3425 1750);
FORCEPROP 1 LAST PATH I408
J 0
(-3425 1950);
DISPLAY 0.978723 (-3425 1950);
PAINT WHITE (-3425 1950);
DISPLAY INVISIBLE (-3425 1950);
FORCEPROP 1 LAST MATERIAL X7R
J 0
(-3075 1700);
DISPLAY 0.978723 (-3075 1700);
PAINT SKYBLUE (-3075 1700);
DISPLAY INVISIBLE (-3075 1700);
FORCEPROP 1 LAST TOLERANCE 10%
J 2
(-3150 1700);
DISPLAY 0.978723 (-3150 1700);
PAINT SKYBLUE (-3150 1700);
DISPLAY INVISIBLE (-3150 1700);
FORCEPROP 1 LAST PART_NUMBER CH4103K1B08
J 1
(-2675 1750);
DISPLAY 0.978723 (-2675 1750);
PAINT SKYBLUE (-2675 1750);
DISPLAY INVISIBLE (-2675 1750);
FORCEPROP 1 LAST VOLTAGE 16V
J 0
(-2900 1700);
DISPLAY 0.978723 (-2900 1700);
PAINT SKYBLUE (-2900 1700);
DISPLAY INVISIBLE (-2900 1700);
FORCEPROP 1 LAST PACK_TYPE C0402
J 1
(-2575 1700);
DISPLAY 0.978723 (-2575 1700);
PAINT SKYBLUE (-2575 1700);
DISPLAY INVISIBLE (-2575 1700);
FORCEADD Q_CAP..2
(-3425 1850);
FORCEPROP 1 LAST LOCATION C1127
J 0
(-3725 1850);
DISPLAY 0.489362 (-3725 1850);
PAINT SKYBLUE (-3725 1850);
FORCEPROP 0 LAST $SEC 1
J 0
(-3050 1900);
DISPLAY 0.680851 (-3050 1900);
PAINT MONO (-3050 1900);
DISPLAY INVISIBLE (-3050 1900);
FORCEPROP 0 LAST CDS_SEC 1
J 0
(-3050 1900);
DISPLAY 1.021277 (-3050 1900);
DISPLAY INVISIBLE (-3050 1900);
FORCEPROP 1 LASTPIN (-3525 1850) $PN 1
J 0
(-3535 1865);
DISPLAY 0.489362 (-3535 1865);
PAINT MONO (-3535 1865);
FORCEPROP 1 LASTPIN (-3325 1850) $PN 2
J 0
(-3340 1865);
DISPLAY 0.489362 (-3340 1865);
PAINT MONO (-3340 1865);
FORCEPROP 1 LAST VALUE 0.1UF
J 2
(-3050 1850);
DISPLAY 0.489362 (-3050 1850);
PAINT SKYBLUE (-3050 1850);
FORCEPROP 2 LAST CDS_LIB pure_quanta
J 0
(-3425 1850);
DISPLAY INVISIBLE (-3425 1850);
FORCEPROP 1 LAST PATH I409
J 0
(-3425 2050);
DISPLAY 0.978723 (-3425 2050);
PAINT WHITE (-3425 2050);
DISPLAY INVISIBLE (-3425 2050);
FORCEPROP 1 LAST MATERIAL X7R
J 0
(-3075 1800);
DISPLAY 0.978723 (-3075 1800);
PAINT SKYBLUE (-3075 1800);
DISPLAY INVISIBLE (-3075 1800);
FORCEPROP 1 LAST TOLERANCE 10%
J 2
(-3150 1800);
DISPLAY 0.978723 (-3150 1800);
PAINT SKYBLUE (-3150 1800);
DISPLAY INVISIBLE (-3150 1800);
FORCEPROP 1 LAST PART_NUMBER CH4103K1B08
J 1
(-2675 1850);
DISPLAY 0.978723 (-2675 1850);
PAINT SKYBLUE (-2675 1850);
DISPLAY INVISIBLE (-2675 1850);
FORCEPROP 1 LAST VOLTAGE 16V
J 0
(-2900 1800);
DISPLAY 0.978723 (-2900 1800);
PAINT SKYBLUE (-2900 1800);
DISPLAY INVISIBLE (-2900 1800);
FORCEPROP 1 LAST PACK_TYPE C0402
J 1
(-2575 1800);
DISPLAY 0.978723 (-2575 1800);
PAINT SKYBLUE (-2575 1800);
DISPLAY INVISIBLE (-2575 1800);
FORCEADD Q_CAP..2
(-3425 1250);
FORCEPROP 1 LAST LOCATION C1132
J 0
(-3725 1250);
DISPLAY 0.489362 (-3725 1250);
PAINT SKYBLUE (-3725 1250);
FORCEPROP 0 LAST $SEC 1
J 0
(-3050 1300);
DISPLAY 0.680851 (-3050 1300);
PAINT MONO (-3050 1300);
DISPLAY INVISIBLE (-3050 1300);
FORCEPROP 0 LAST CDS_SEC 1
J 0
(-3050 1300);
DISPLAY 1.021277 (-3050 1300);
DISPLAY INVISIBLE (-3050 1300);
FORCEPROP 1 LASTPIN (-3525 1250) $PN 1
J 0
(-3535 1265);
DISPLAY 0.489362 (-3535 1265);
PAINT MONO (-3535 1265);
FORCEPROP 1 LASTPIN (-3325 1250) $PN 2
J 0
(-3340 1265);
DISPLAY 0.489362 (-3340 1265);
PAINT MONO (-3340 1265);
FORCEPROP 1 LAST VALUE 0.1UF
J 2
(-3050 1250);
DISPLAY 0.489362 (-3050 1250);
PAINT SKYBLUE (-3050 1250);
FORCEPROP 2 LAST CDS_LIB pure_quanta
J 0
(-3425 1250);
DISPLAY INVISIBLE (-3425 1250);
FORCEPROP 1 LAST PATH I411
J 0
(-3425 1450);
DISPLAY 0.978723 (-3425 1450);
PAINT WHITE (-3425 1450);
DISPLAY INVISIBLE (-3425 1450);
FORCEPROP 1 LAST MATERIAL X7R
J 0
(-3075 1200);
DISPLAY 0.978723 (-3075 1200);
PAINT SKYBLUE (-3075 1200);
DISPLAY INVISIBLE (-3075 1200);
FORCEPROP 1 LAST TOLERANCE 10%
J 2
(-3150 1200);
DISPLAY 0.978723 (-3150 1200);
PAINT SKYBLUE (-3150 1200);
DISPLAY INVISIBLE (-3150 1200);
FORCEPROP 1 LAST PART_NUMBER CH4103K1B08
J 1
(-2675 1250);
DISPLAY 0.978723 (-2675 1250);
PAINT SKYBLUE (-2675 1250);
DISPLAY INVISIBLE (-2675 1250);
FORCEPROP 1 LAST VOLTAGE 16V
J 0
(-2900 1200);
DISPLAY 0.978723 (-2900 1200);
PAINT SKYBLUE (-2900 1200);
DISPLAY INVISIBLE (-2900 1200);
FORCEPROP 1 LAST PACK_TYPE C0402
J 1
(-2575 1200);
DISPLAY 0.978723 (-2575 1200);
PAINT SKYBLUE (-2575 1200);
DISPLAY INVISIBLE (-2575 1200);
FORCEADD Q_CAP..2
(-3425 1350);
FORCEPROP 1 LAST LOCATION C1131
J 0
(-3725 1350);
DISPLAY 0.489362 (-3725 1350);
PAINT SKYBLUE (-3725 1350);
FORCEPROP 0 LAST $SEC 1
J 0
(-3050 1400);
DISPLAY 0.680851 (-3050 1400);
PAINT MONO (-3050 1400);
DISPLAY INVISIBLE (-3050 1400);
FORCEPROP 0 LAST CDS_SEC 1
J 0
(-3050 1400);
DISPLAY 1.021277 (-3050 1400);
DISPLAY INVISIBLE (-3050 1400);
FORCEPROP 1 LASTPIN (-3525 1350) $PN 1
J 0
(-3535 1365);
DISPLAY 0.489362 (-3535 1365);
PAINT MONO (-3535 1365);
FORCEPROP 1 LASTPIN (-3325 1350) $PN 2
J 0
(-3340 1365);
DISPLAY 0.489362 (-3340 1365);
PAINT MONO (-3340 1365);
FORCEPROP 1 LAST VALUE 0.1UF
J 2
(-3050 1350);
DISPLAY 0.489362 (-3050 1350);
PAINT SKYBLUE (-3050 1350);
FORCEPROP 2 LAST CDS_LIB pure_quanta
J 0
(-3425 1350);
DISPLAY INVISIBLE (-3425 1350);
FORCEPROP 1 LAST PATH I412
J 0
(-3425 1550);
DISPLAY 0.978723 (-3425 1550);
PAINT WHITE (-3425 1550);
DISPLAY INVISIBLE (-3425 1550);
FORCEPROP 1 LAST MATERIAL X7R
J 0
(-3075 1300);
DISPLAY 0.978723 (-3075 1300);
PAINT SKYBLUE (-3075 1300);
DISPLAY INVISIBLE (-3075 1300);
FORCEPROP 1 LAST TOLERANCE 10%
J 2
(-3150 1300);
DISPLAY 0.978723 (-3150 1300);
PAINT SKYBLUE (-3150 1300);
DISPLAY INVISIBLE (-3150 1300);
FORCEPROP 1 LAST PART_NUMBER CH4103K1B08
J 1
(-2675 1350);
DISPLAY 0.978723 (-2675 1350);
PAINT SKYBLUE (-2675 1350);
DISPLAY INVISIBLE (-2675 1350);
FORCEPROP 1 LAST VOLTAGE 16V
J 0
(-2900 1300);
DISPLAY 0.978723 (-2900 1300);
PAINT SKYBLUE (-2900 1300);
DISPLAY INVISIBLE (-2900 1300);
FORCEPROP 1 LAST PACK_TYPE C0402
J 1
(-2575 1300);
DISPLAY 0.978723 (-2575 1300);
PAINT SKYBLUE (-2575 1300);
DISPLAY INVISIBLE (-2575 1300);
FORCEADD Q_CAP..2
(-3425 1550);
FORCEPROP 1 LAST LOCATION C352
J 0
(-3725 1550);
DISPLAY 0.489362 (-3725 1550);
PAINT SKYBLUE (-3725 1550);
FORCEPROP 2 LAST $SEC 1
J 0
(-3425 1800);
DISPLAY 0.680851 (-3425 1800);
PAINT MONO (-3425 1800);
DISPLAY INVISIBLE (-3425 1800);
FORCEPROP 2 LAST CDS_SEC 1
J 0
(-3425 1800);
DISPLAY 1.021277 (-3425 1800);
DISPLAY INVISIBLE (-3425 1800);
FORCEPROP 1 LASTPIN (-3525 1550) $PN 1
J 0
(-3535 1565);
DISPLAY 0.489362 (-3535 1565);
PAINT MONO (-3535 1565);
FORCEPROP 1 LASTPIN (-3325 1550) $PN 2
J 0
(-3340 1565);
DISPLAY 0.489362 (-3340 1565);
PAINT MONO (-3340 1565);
FORCEPROP 1 LAST VALUE 0.1UF
J 2
(-3050 1550);
DISPLAY 0.489362 (-3050 1550);
PAINT SKYBLUE (-3050 1550);
FORCEPROP 2 LAST CDS_LIB pure_quanta
J 0
(-3425 1550);
DISPLAY INVISIBLE (-3425 1550);
FORCEPROP 1 LAST PATH I413
J 0
(-3425 1750);
DISPLAY 0.978723 (-3425 1750);
PAINT WHITE (-3425 1750);
DISPLAY INVISIBLE (-3425 1750);
FORCEPROP 1 LAST MATERIAL X7R
J 0
(-3075 1500);
DISPLAY 0.489362 (-3075 1500);
PAINT SKYBLUE (-3075 1500);
DISPLAY INVISIBLE (-3075 1500);
FORCEPROP 1 LAST TOLERANCE 10%
J 2
(-3150 1500);
DISPLAY 0.489362 (-3150 1500);
PAINT SKYBLUE (-3150 1500);
DISPLAY INVISIBLE (-3150 1500);
FORCEPROP 1 LAST PART_NUMBER CH4103K1B08
J 1
(-2675 1550);
DISPLAY 0.489362 (-2675 1550);
PAINT SKYBLUE (-2675 1550);
DISPLAY INVISIBLE (-2675 1550);
FORCEPROP 1 LAST VOLTAGE 16V
J 0
(-2900 1500);
DISPLAY 0.489362 (-2900 1500);
PAINT SKYBLUE (-2900 1500);
DISPLAY INVISIBLE (-2900 1500);
FORCEPROP 1 LAST PACK_TYPE C0402
J 1
(-2575 1500);
DISPLAY 0.489362 (-2575 1500);
PAINT SKYBLUE (-2575 1500);
DISPLAY INVISIBLE (-2575 1500);
FORCEADD Q_CAP..2
(-3425 1650);
FORCEPROP 1 LAST LOCATION C1129
J 0
(-3725 1650);
DISPLAY 0.489362 (-3725 1650);
PAINT SKYBLUE (-3725 1650);
FORCEPROP 0 LAST $SEC 1
J 0
(-3050 1700);
DISPLAY 0.680851 (-3050 1700);
PAINT MONO (-3050 1700);
DISPLAY INVISIBLE (-3050 1700);
FORCEPROP 0 LAST CDS_SEC 1
J 0
(-3050 1700);
DISPLAY 1.021277 (-3050 1700);
DISPLAY INVISIBLE (-3050 1700);
FORCEPROP 1 LASTPIN (-3525 1650) $PN 1
J 0
(-3535 1665);
DISPLAY 0.489362 (-3535 1665);
PAINT MONO (-3535 1665);
FORCEPROP 1 LASTPIN (-3325 1650) $PN 2
J 0
(-3340 1665);
DISPLAY 0.489362 (-3340 1665);
PAINT MONO (-3340 1665);
FORCEPROP 1 LAST VALUE 0.1UF
J 2
(-3050 1650);
DISPLAY 0.489362 (-3050 1650);
PAINT SKYBLUE (-3050 1650);
FORCEPROP 2 LAST CDS_LIB pure_quanta
J 0
(-3425 1650);
DISPLAY INVISIBLE (-3425 1650);
FORCEPROP 1 LAST PATH I414
J 0
(-3425 1850);
DISPLAY 0.978723 (-3425 1850);
PAINT WHITE (-3425 1850);
DISPLAY INVISIBLE (-3425 1850);
FORCEPROP 1 LAST MATERIAL X7R
J 0
(-3075 1600);
DISPLAY 0.978723 (-3075 1600);
PAINT SKYBLUE (-3075 1600);
DISPLAY INVISIBLE (-3075 1600);
FORCEPROP 1 LAST TOLERANCE 10%
J 2
(-3150 1600);
DISPLAY 0.978723 (-3150 1600);
PAINT SKYBLUE (-3150 1600);
DISPLAY INVISIBLE (-3150 1600);
FORCEPROP 1 LAST PART_NUMBER CH4103K1B08
J 1
(-2675 1650);
DISPLAY 0.978723 (-2675 1650);
PAINT SKYBLUE (-2675 1650);
DISPLAY INVISIBLE (-2675 1650);
FORCEPROP 1 LAST VOLTAGE 16V
J 0
(-2900 1600);
DISPLAY 0.978723 (-2900 1600);
PAINT SKYBLUE (-2900 1600);
DISPLAY INVISIBLE (-2900 1600);
FORCEPROP 1 LAST PACK_TYPE C0402
J 1
(-2575 1600);
DISPLAY 0.978723 (-2575 1600);
PAINT SKYBLUE (-2575 1600);
DISPLAY INVISIBLE (-2575 1600);
FORCEADD Q_CAP..2
(-3425 1150);
FORCEPROP 1 LAST LOCATION C1133
J 0
(-3725 1150);
DISPLAY 0.489362 (-3725 1150);
PAINT SKYBLUE (-3725 1150);
FORCEPROP 0 LAST $SEC 1
J 0
(-3050 1200);
DISPLAY 0.680851 (-3050 1200);
PAINT MONO (-3050 1200);
DISPLAY INVISIBLE (-3050 1200);
FORCEPROP 0 LAST CDS_SEC 1
J 0
(-3050 1200);
DISPLAY 1.021277 (-3050 1200);
DISPLAY INVISIBLE (-3050 1200);
FORCEPROP 1 LASTPIN (-3525 1150) $PN 1
J 0
(-3535 1165);
DISPLAY 0.489362 (-3535 1165);
PAINT MONO (-3535 1165);
FORCEPROP 1 LASTPIN (-3325 1150) $PN 2
J 0
(-3340 1165);
DISPLAY 0.489362 (-3340 1165);
PAINT MONO (-3340 1165);
FORCEPROP 1 LAST VALUE 0.1UF
J 2
(-3050 1150);
DISPLAY 0.489362 (-3050 1150);
PAINT SKYBLUE (-3050 1150);
FORCEPROP 2 LAST CDS_LIB pure_quanta
J 0
(-3425 1150);
DISPLAY INVISIBLE (-3425 1150);
FORCEPROP 1 LAST PATH I415
J 0
(-3425 1350);
DISPLAY 0.978723 (-3425 1350);
PAINT WHITE (-3425 1350);
DISPLAY INVISIBLE (-3425 1350);
FORCEPROP 1 LAST MATERIAL X7R
J 0
(-3075 1100);
DISPLAY 0.978723 (-3075 1100);
PAINT SKYBLUE (-3075 1100);
DISPLAY INVISIBLE (-3075 1100);
FORCEPROP 1 LAST TOLERANCE 10%
J 2
(-3150 1100);
DISPLAY 0.978723 (-3150 1100);
PAINT SKYBLUE (-3150 1100);
DISPLAY INVISIBLE (-3150 1100);
FORCEPROP 1 LAST PART_NUMBER CH4103K1B08
J 1
(-2675 1150);
DISPLAY 0.978723 (-2675 1150);
PAINT SKYBLUE (-2675 1150);
DISPLAY INVISIBLE (-2675 1150);
FORCEPROP 1 LAST VOLTAGE 16V
J 0
(-2900 1100);
DISPLAY 0.978723 (-2900 1100);
PAINT SKYBLUE (-2900 1100);
DISPLAY INVISIBLE (-2900 1100);
FORCEPROP 1 LAST PACK_TYPE C0402
J 1
(-2575 1100);
DISPLAY 0.978723 (-2575 1100);
PAINT SKYBLUE (-2575 1100);
DISPLAY INVISIBLE (-2575 1100);
FORCEADD Q_CAP..2
(-3425 1050);
FORCEPROP 1 LAST LOCATION C1134
J 0
(-3725 1050);
DISPLAY 0.489362 (-3725 1050);
PAINT SKYBLUE (-3725 1050);
FORCEPROP 0 LAST $SEC 1
J 0
(-3050 1100);
DISPLAY 0.680851 (-3050 1100);
PAINT MONO (-3050 1100);
DISPLAY INVISIBLE (-3050 1100);
FORCEPROP 0 LAST CDS_SEC 1
J 0
(-3050 1100);
DISPLAY 1.021277 (-3050 1100);
DISPLAY INVISIBLE (-3050 1100);
FORCEPROP 1 LASTPIN (-3525 1050) $PN 1
J 0
(-3535 1065);
DISPLAY 0.489362 (-3535 1065);
PAINT MONO (-3535 1065);
FORCEPROP 1 LASTPIN (-3325 1050) $PN 2
J 0
(-3340 1065);
DISPLAY 0.489362 (-3340 1065);
PAINT MONO (-3340 1065);
FORCEPROP 1 LAST VALUE 0.1UF
J 2
(-3050 1050);
DISPLAY 0.489362 (-3050 1050);
PAINT SKYBLUE (-3050 1050);
FORCEPROP 2 LAST CDS_LIB pure_quanta
J 0
(-3425 1050);
DISPLAY INVISIBLE (-3425 1050);
FORCEPROP 1 LAST PATH I416
J 0
(-3425 1250);
DISPLAY 0.978723 (-3425 1250);
PAINT WHITE (-3425 1250);
DISPLAY INVISIBLE (-3425 1250);
FORCEPROP 1 LAST MATERIAL X7R
J 0
(-3075 1000);
DISPLAY 0.978723 (-3075 1000);
PAINT SKYBLUE (-3075 1000);
DISPLAY INVISIBLE (-3075 1000);
FORCEPROP 1 LAST TOLERANCE 10%
J 2
(-3150 1000);
DISPLAY 0.978723 (-3150 1000);
PAINT SKYBLUE (-3150 1000);
DISPLAY INVISIBLE (-3150 1000);
FORCEPROP 1 LAST PART_NUMBER CH4103K1B08
J 1
(-2675 1050);
DISPLAY 0.978723 (-2675 1050);
PAINT SKYBLUE (-2675 1050);
DISPLAY INVISIBLE (-2675 1050);
FORCEPROP 1 LAST VOLTAGE 16V
J 0
(-2900 1000);
DISPLAY 0.978723 (-2900 1000);
PAINT SKYBLUE (-2900 1000);
DISPLAY INVISIBLE (-2900 1000);
FORCEPROP 1 LAST PACK_TYPE C0402
J 1
(-2575 1000);
DISPLAY 0.978723 (-2575 1000);
PAINT SKYBLUE (-2575 1000);
DISPLAY INVISIBLE (-2575 1000);
FORCEADD VCC_CORE..1
(-3800 2125);
FORCEPROP 3 LASTPIN (-3800 2075) SIG_NAME P1V8_STBY\g
J 0
(-3790 2085);
DISPLAY 0.659574 (-3790 2085);
PAINT MONO (-3790 2085);
DISPLAY INVISIBLE (-3790 2085);
FORCEPROP 1 LAST HDL_POWER P1V8_STBY
J 1
(-3800 2175);
DISPLAY 0.489362 (-3800 2175);
PAINT GREEN (-3800 2175);
FORCEPROP 2 LAST CDS_LIB pure_quanta_power
J 0
(-3800 2125);
DISPLAY INVISIBLE (-3800 2125);
FORCEPROP 1 LAST PATH I419
J 0
(-3750 2150);
DISPLAY 0.872340 (-3750 2150);
PAINT AQUA (-3750 2150);
DISPLAY INVISIBLE (-3750 2150);
FORCEADD GND..1
(-3600 4225);
FORCEPROP 3 LASTPIN (-3600 4275) SIG_NAME GND\g
J 0
(-3590 4285);
DISPLAY 0.659574 (-3590 4285);
PAINT MONO (-3590 4285);
DISPLAY INVISIBLE (-3590 4285);
FORCEPROP 2 LAST BOM_COST MEM
J 0
(-3700 4300);
DISPLAY 0.808511 (-3700 4300);
DISPLAY INVISIBLE (-3700 4300);
FORCEPROP 1 LAST SIZE 1B
J 0
(-3525 4175);
DISPLAY 0.851064 (-3525 4175);
PAINT GREEN (-3525 4175);
DISPLAY INVISIBLE (-3525 4175);
FORCEPROP 2 LAST CDS_LIB pure_quanta_power
J 0
(-3600 4225);
DISPLAY INVISIBLE (-3600 4225);
FORCEPROP 1 LAST PATH I692
J 0
(-3525 4225);
DISPLAY 0.872340 (-3525 4225);
PAINT AQUA (-3525 4225);
DISPLAY INVISIBLE (-3525 4225);
FORCEPROP 1 LAST HDL_POWER GND
J 0
(-3600 4375);
DISPLAY 0.851064 (-3600 4375);
PAINT GREEN (-3600 4375);
DISPLAY INVISIBLE (-3600 4375);
FORCEADD OFFPAGE..2
(-1375 5125);
FORCEPROP 2 LAST $XR1 125 
J 0
(-1096 5125);
DISPLAY 0.638298 (-1096 5125);
PAINT MONO (-1096 5125);
FORCEPROP 2 LAST $XR0 80 
J 0
(-1186 5125);
DISPLAY 0.638298 (-1186 5125);
PAINT MONO (-1186 5125);
FORCEPROP 2 LAST PATH I693
J 0
(-1075 5175);
DISPLAY 0.680851 (-1075 5175);
DISPLAY INVISIBLE (-1075 5175);
FORCEPROP 1 LAST COMMENT_BODY TRUE
J 0
(-1420 5030);
DISPLAY 0.872340 (-1420 5030);
PAINT GREEN (-1420 5030);
DISPLAY INVISIBLE (-1420 5030);
FORCEPROP 1 LAST OFFPAGE TRUE
J 0
(-1050 5000);
DISPLAY 0.872340 (-1050 5000);
PAINT GREEN (-1050 5000);
DISPLAY INVISIBLE (-1050 5000);
FORCEPROP 2 LAST CDS_LIB standard
J 0
(-1375 5125);
DISPLAY INVISIBLE (-1375 5125);
FORCEADD OFFPAGE..2
(-1375 5175);
FORCEPROP 2 LAST $XR1 124 
J 0
(-1096 5175);
DISPLAY 0.638298 (-1096 5175);
PAINT MONO (-1096 5175);
FORCEPROP 2 LAST $XR0 80 
J 0
(-1186 5175);
DISPLAY 0.638298 (-1186 5175);
PAINT MONO (-1186 5175);
FORCEPROP 2 LAST PATH I694
J 0
(-1075 5225);
DISPLAY 0.680851 (-1075 5225);
DISPLAY INVISIBLE (-1075 5225);
FORCEPROP 1 LAST COMMENT_BODY TRUE
J 0
(-1420 5080);
DISPLAY 0.872340 (-1420 5080);
PAINT GREEN (-1420 5080);
DISPLAY INVISIBLE (-1420 5080);
FORCEPROP 1 LAST OFFPAGE TRUE
J 0
(-1050 5050);
DISPLAY 0.872340 (-1050 5050);
PAINT GREEN (-1050 5050);
DISPLAY INVISIBLE (-1050 5050);
FORCEPROP 2 LAST CDS_LIB standard
J 0
(-1375 5175);
DISPLAY INVISIBLE (-1375 5175);
FORCEADD OFFPAGE..2
(-1375 5075);
FORCEPROP 2 LAST $XR1 126 
J 0
(-1096 5075);
DISPLAY 0.638298 (-1096 5075);
PAINT MONO (-1096 5075);
FORCEPROP 2 LAST $XR0 80 
J 0
(-1186 5075);
DISPLAY 0.638298 (-1186 5075);
PAINT MONO (-1186 5075);
FORCEPROP 2 LAST PATH I695
J 0
(-1075 5125);
DISPLAY 0.680851 (-1075 5125);
DISPLAY INVISIBLE (-1075 5125);
FORCEPROP 1 LAST COMMENT_BODY TRUE
J 0
(-1420 4980);
DISPLAY 0.872340 (-1420 4980);
PAINT GREEN (-1420 4980);
DISPLAY INVISIBLE (-1420 4980);
FORCEPROP 1 LAST OFFPAGE TRUE
J 0
(-1050 4950);
DISPLAY 0.872340 (-1050 4950);
PAINT GREEN (-1050 4950);
DISPLAY INVISIBLE (-1050 4950);
FORCEPROP 2 LAST CDS_LIB standard
J 0
(-1375 5075);
DISPLAY INVISIBLE (-1375 5075);
FORCEADD OFFPAGE..2
(-1375 4975);
FORCEPROP 2 LAST $XR1 128 
J 0
(-1096 4975);
DISPLAY 0.638298 (-1096 4975);
PAINT MONO (-1096 4975);
FORCEPROP 2 LAST $XR0 80 
J 0
(-1186 4975);
DISPLAY 0.638298 (-1186 4975);
PAINT MONO (-1186 4975);
FORCEPROP 2 LAST PATH I696
J 0
(-1075 5025);
DISPLAY 0.680851 (-1075 5025);
DISPLAY INVISIBLE (-1075 5025);
FORCEPROP 1 LAST COMMENT_BODY TRUE
J 0
(-1420 4880);
DISPLAY 0.872340 (-1420 4880);
PAINT GREEN (-1420 4880);
DISPLAY INVISIBLE (-1420 4880);
FORCEPROP 1 LAST OFFPAGE TRUE
J 0
(-1050 4850);
DISPLAY 0.872340 (-1050 4850);
PAINT GREEN (-1050 4850);
DISPLAY INVISIBLE (-1050 4850);
FORCEPROP 2 LAST CDS_LIB standard
J 0
(-1375 4975);
DISPLAY INVISIBLE (-1375 4975);
FORCEADD OFFPAGE..2
(-1375 5025);
FORCEPROP 2 LAST $XR1 127 
J 0
(-1096 5025);
DISPLAY 0.638298 (-1096 5025);
PAINT MONO (-1096 5025);
FORCEPROP 2 LAST $XR0 80 
J 0
(-1186 5025);
DISPLAY 0.638298 (-1186 5025);
PAINT MONO (-1186 5025);
FORCEPROP 2 LAST PATH I697
J 0
(-1075 5075);
DISPLAY 0.680851 (-1075 5075);
DISPLAY INVISIBLE (-1075 5075);
FORCEPROP 1 LAST COMMENT_BODY TRUE
J 0
(-1420 4930);
DISPLAY 0.872340 (-1420 4930);
PAINT GREEN (-1420 4930);
DISPLAY INVISIBLE (-1420 4930);
FORCEPROP 1 LAST OFFPAGE TRUE
J 0
(-1050 4900);
DISPLAY 0.872340 (-1050 4900);
PAINT GREEN (-1050 4900);
DISPLAY INVISIBLE (-1050 4900);
FORCEPROP 2 LAST CDS_LIB standard
J 0
(-1375 5025);
DISPLAY INVISIBLE (-1375 5025);
FORCEADD OFFPAGE..2
(-1375 4925);
FORCEPROP 2 LAST $XR1 128 
J 0
(-1096 4925);
DISPLAY 0.638298 (-1096 4925);
PAINT MONO (-1096 4925);
FORCEPROP 2 LAST $XR0 80 
J 0
(-1186 4925);
DISPLAY 0.638298 (-1186 4925);
PAINT MONO (-1186 4925);
FORCEPROP 2 LAST PATH I698
J 0
(-1075 4975);
DISPLAY 0.680851 (-1075 4975);
DISPLAY INVISIBLE (-1075 4975);
FORCEPROP 1 LAST COMMENT_BODY TRUE
J 0
(-1420 4830);
DISPLAY 0.872340 (-1420 4830);
PAINT GREEN (-1420 4830);
DISPLAY INVISIBLE (-1420 4830);
FORCEPROP 1 LAST OFFPAGE TRUE
J 0
(-1050 4800);
DISPLAY 0.872340 (-1050 4800);
PAINT GREEN (-1050 4800);
DISPLAY INVISIBLE (-1050 4800);
FORCEPROP 2 LAST CDS_LIB standard
J 0
(-1375 4925);
DISPLAY INVISIBLE (-1375 4925);
FORCEADD OFFPAGE..2
(-1375 4825);
FORCEPROP 2 LAST $XR1 114 
J 0
(-1096 4825);
DISPLAY 0.638298 (-1096 4825);
PAINT MONO (-1096 4825);
FORCEPROP 2 LAST $XR0 80 
J 0
(-1186 4825);
DISPLAY 0.638298 (-1186 4825);
PAINT MONO (-1186 4825);
FORCEPROP 2 LAST PATH I699
J 0
(-1075 4875);
DISPLAY 0.680851 (-1075 4875);
DISPLAY INVISIBLE (-1075 4875);
FORCEPROP 1 LAST COMMENT_BODY TRUE
J 0
(-1420 4730);
DISPLAY 0.872340 (-1420 4730);
PAINT GREEN (-1420 4730);
DISPLAY INVISIBLE (-1420 4730);
FORCEPROP 1 LAST OFFPAGE TRUE
J 0
(-1050 4700);
DISPLAY 0.872340 (-1050 4700);
PAINT GREEN (-1050 4700);
DISPLAY INVISIBLE (-1050 4700);
FORCEPROP 2 LAST CDS_LIB standard
J 0
(-1375 4825);
DISPLAY INVISIBLE (-1375 4825);
FORCEADD OFFPAGE..2
(-1375 4875);
FORCEPROP 2 LAST $XR1 114 
J 0
(-1096 4875);
DISPLAY 0.638298 (-1096 4875);
PAINT MONO (-1096 4875);
FORCEPROP 2 LAST $XR0 80 
J 0
(-1186 4875);
DISPLAY 0.638298 (-1186 4875);
PAINT MONO (-1186 4875);
FORCEPROP 2 LAST PATH I700
J 0
(-1075 4925);
DISPLAY 0.680851 (-1075 4925);
DISPLAY INVISIBLE (-1075 4925);
FORCEPROP 1 LAST COMMENT_BODY TRUE
J 0
(-1420 4780);
DISPLAY 0.872340 (-1420 4780);
PAINT GREEN (-1420 4780);
DISPLAY INVISIBLE (-1420 4780);
FORCEPROP 1 LAST OFFPAGE TRUE
J 0
(-1050 4750);
DISPLAY 0.872340 (-1050 4750);
PAINT GREEN (-1050 4750);
DISPLAY INVISIBLE (-1050 4750);
FORCEPROP 2 LAST CDS_LIB standard
J 0
(-1375 4875);
DISPLAY INVISIBLE (-1375 4875);
FORCEADD OFFPAGE..2
(-1375 4775);
FORCEPROP 2 LAST $XR1 115 
J 0
(-1096 4775);
DISPLAY 0.638298 (-1096 4775);
PAINT MONO (-1096 4775);
FORCEPROP 2 LAST $XR0 80 
J 0
(-1186 4775);
DISPLAY 0.638298 (-1186 4775);
PAINT MONO (-1186 4775);
FORCEPROP 2 LAST PATH I701
J 0
(-1075 4825);
DISPLAY 0.680851 (-1075 4825);
DISPLAY INVISIBLE (-1075 4825);
FORCEPROP 1 LAST COMMENT_BODY TRUE
J 0
(-1420 4680);
DISPLAY 0.872340 (-1420 4680);
PAINT GREEN (-1420 4680);
DISPLAY INVISIBLE (-1420 4680);
FORCEPROP 1 LAST OFFPAGE TRUE
J 0
(-1050 4650);
DISPLAY 0.872340 (-1050 4650);
PAINT GREEN (-1050 4650);
DISPLAY INVISIBLE (-1050 4650);
FORCEPROP 2 LAST CDS_LIB standard
J 0
(-1375 4775);
DISPLAY INVISIBLE (-1375 4775);
FORCEADD OFFPAGE..2
(-1375 4675);
FORCEPROP 2 LAST $XR1 116 
J 0
(-1096 4675);
DISPLAY 0.638298 (-1096 4675);
PAINT MONO (-1096 4675);
FORCEPROP 2 LAST $XR0 80 
J 0
(-1186 4675);
DISPLAY 0.638298 (-1186 4675);
PAINT MONO (-1186 4675);
FORCEPROP 2 LAST PATH I702
J 0
(-1075 4725);
DISPLAY 0.680851 (-1075 4725);
DISPLAY INVISIBLE (-1075 4725);
FORCEPROP 1 LAST COMMENT_BODY TRUE
J 0
(-1420 4580);
DISPLAY 0.872340 (-1420 4580);
PAINT GREEN (-1420 4580);
DISPLAY INVISIBLE (-1420 4580);
FORCEPROP 1 LAST OFFPAGE TRUE
J 0
(-1050 4550);
DISPLAY 0.872340 (-1050 4550);
PAINT GREEN (-1050 4550);
DISPLAY INVISIBLE (-1050 4550);
FORCEPROP 2 LAST CDS_LIB standard
J 0
(-1375 4675);
DISPLAY INVISIBLE (-1375 4675);
FORCEADD OFFPAGE..2
(-1375 4725);
FORCEPROP 2 LAST $XR1 115 
J 0
(-1096 4725);
DISPLAY 0.638298 (-1096 4725);
PAINT MONO (-1096 4725);
FORCEPROP 2 LAST $XR0 80 
J 0
(-1186 4725);
DISPLAY 0.638298 (-1186 4725);
PAINT MONO (-1186 4725);
FORCEPROP 2 LAST PATH I703
J 0
(-1075 4775);
DISPLAY 0.680851 (-1075 4775);
DISPLAY INVISIBLE (-1075 4775);
FORCEPROP 1 LAST COMMENT_BODY TRUE
J 0
(-1420 4630);
DISPLAY 0.872340 (-1420 4630);
PAINT GREEN (-1420 4630);
DISPLAY INVISIBLE (-1420 4630);
FORCEPROP 1 LAST OFFPAGE TRUE
J 0
(-1050 4600);
DISPLAY 0.872340 (-1050 4600);
PAINT GREEN (-1050 4600);
DISPLAY INVISIBLE (-1050 4600);
FORCEPROP 2 LAST CDS_LIB standard
J 0
(-1375 4725);
DISPLAY INVISIBLE (-1375 4725);
FORCEADD OFFPAGE..1
R 2
(-2000 6200);
FORCEPROP 2 LAST $XR1 80 
J 0
(-1724 6200);
DISPLAY 0.638298 (-1724 6200);
PAINT MONO (-1724 6200);
FORCEPROP 2 LAST $XR0 28 
J 0
(-1814 6200);
DISPLAY 0.638298 (-1814 6200);
PAINT MONO (-1814 6200);
FORCEPROP 2 LAST PATH I704
J 0
(-1700 6250);
DISPLAY 0.680851 (-1700 6250);
DISPLAY INVISIBLE (-1700 6250);
FORCEPROP 1 LAST COMMENT_BODY TRUE
J 2
(-2125 6100);
DISPLAY 0.872340 (-2125 6100);
PAINT GREEN (-2125 6100);
DISPLAY INVISIBLE (-2125 6100);
FORCEPROP 1 LAST OFFPAGE TRUE
J 2
(-2325 6075);
DISPLAY 0.872340 (-2325 6075);
PAINT GREEN (-2325 6075);
DISPLAY INVISIBLE (-2325 6075);
FORCEPROP 2 LAST CDS_LIB standard
J 0
(-2000 6200);
DISPLAY INVISIBLE (-2000 6200);
FORCEADD OFFPAGE..1
R 2
(-2000 6150);
FORCEPROP 2 LAST $XR1 80 
J 0
(-1724 6150);
DISPLAY 0.638298 (-1724 6150);
PAINT MONO (-1724 6150);
FORCEPROP 2 LAST $XR0 28 
J 0
(-1814 6150);
DISPLAY 0.638298 (-1814 6150);
PAINT MONO (-1814 6150);
FORCEPROP 2 LAST PATH I705
J 0
(-1700 6200);
DISPLAY 0.680851 (-1700 6200);
DISPLAY INVISIBLE (-1700 6200);
FORCEPROP 1 LAST COMMENT_BODY TRUE
J 2
(-2125 6050);
DISPLAY 0.872340 (-2125 6050);
PAINT GREEN (-2125 6050);
DISPLAY INVISIBLE (-2125 6050);
FORCEPROP 1 LAST OFFPAGE TRUE
J 2
(-2325 6025);
DISPLAY 0.872340 (-2325 6025);
PAINT GREEN (-2325 6025);
DISPLAY INVISIBLE (-2325 6025);
FORCEPROP 2 LAST CDS_LIB standard
J 0
(-2000 6150);
DISPLAY INVISIBLE (-2000 6150);
FORCEADD OFFPAGE..1
R 2
(-2000 6100);
FORCEPROP 2 LAST $XR1 80 
J 0
(-1724 6100);
DISPLAY 0.638298 (-1724 6100);
PAINT MONO (-1724 6100);
FORCEPROP 2 LAST $XR0 55 
J 0
(-1814 6100);
DISPLAY 0.638298 (-1814 6100);
PAINT MONO (-1814 6100);
FORCEPROP 2 LAST PATH I706
J 0
(-1700 6150);
DISPLAY 0.680851 (-1700 6150);
DISPLAY INVISIBLE (-1700 6150);
FORCEPROP 1 LAST COMMENT_BODY TRUE
J 2
(-2125 6000);
DISPLAY 0.872340 (-2125 6000);
PAINT GREEN (-2125 6000);
DISPLAY INVISIBLE (-2125 6000);
FORCEPROP 1 LAST OFFPAGE TRUE
J 2
(-2325 5975);
DISPLAY 0.872340 (-2325 5975);
PAINT GREEN (-2325 5975);
DISPLAY INVISIBLE (-2325 5975);
FORCEPROP 2 LAST CDS_LIB standard
J 0
(-2000 6100);
DISPLAY INVISIBLE (-2000 6100);
FORCEADD OFFPAGE..1
R 2
(-2000 6050);
FORCEPROP 2 LAST $XR1 80 
J 0
(-1724 6050);
DISPLAY 0.638298 (-1724 6050);
PAINT MONO (-1724 6050);
FORCEPROP 2 LAST $XR0 55 
J 0
(-1814 6050);
DISPLAY 0.638298 (-1814 6050);
PAINT MONO (-1814 6050);
FORCEPROP 2 LAST PATH I707
J 0
(-1700 6100);
DISPLAY 0.680851 (-1700 6100);
DISPLAY INVISIBLE (-1700 6100);
FORCEPROP 1 LAST COMMENT_BODY TRUE
J 2
(-2125 5950);
DISPLAY 0.872340 (-2125 5950);
PAINT GREEN (-2125 5950);
DISPLAY INVISIBLE (-2125 5950);
FORCEPROP 1 LAST OFFPAGE TRUE
J 2
(-2325 5925);
DISPLAY 0.872340 (-2325 5925);
PAINT GREEN (-2325 5925);
DISPLAY INVISIBLE (-2325 5925);
FORCEPROP 2 LAST CDS_LIB standard
J 0
(-2000 6050);
DISPLAY INVISIBLE (-2000 6050);
FORCEADD Q_RES..2
(-2850 5775);
FORCEPROP 1 LAST LOCATION R19
J 0
(-2825 5900);
DISPLAY 0.489362 (-2825 5900);
PAINT SKYBLUE (-2825 5900);
FORCEPROP 0 LAST $SEC 1
J 0
(-2800 5950);
DISPLAY 0.680851 (-2800 5950);
PAINT MONO (-2800 5950);
DISPLAY INVISIBLE (-2800 5950);
FORCEPROP 0 LAST CDS_SEC 1
J 0
(-2800 5950);
DISPLAY 1.021277 (-2800 5950);
DISPLAY INVISIBLE (-2800 5950);
FORCEPROP 1 LASTPIN (-2850 5875) $PN 1
J 0
(-2845 5837);
DISPLAY 0.489362 (-2845 5837);
PAINT MONO (-2845 5837);
FORCEPROP 1 LASTPIN (-2850 5675) $PN 2
J 0
(-2845 5685);
DISPLAY 0.489362 (-2845 5685);
PAINT MONO (-2845 5685);
FORCEPROP 1 LAST WATTAGE 1/16W
J 0
(-2810 5750);
DISPLAY 0.489362 (-2810 5750);
PAINT SKYBLUE (-2810 5750);
FORCEPROP 1 LAST MATERIAL CHIP
J 0
(-2810 5700);
DISPLAY 0.489362 (-2810 5700);
PAINT SKYBLUE (-2810 5700);
FORCEPROP 1 LAST TOLERANCE 1%
J 0
(-2805 5800);
DISPLAY 0.489362 (-2805 5800);
PAINT SKYBLUE (-2805 5800);
FORCEPROP 1 LAST VALUE 10K
J 0
(-2805 5850);
DISPLAY 0.489362 (-2805 5850);
PAINT SKYBLUE (-2805 5850);
FORCEPROP 1 LAST PACK_TYPE 0402LF
J 0
(-2800 5650);
DISPLAY 0.489362 (-2800 5650);
PAINT SKYBLUE (-2800 5650);
FORCEPROP 2 LAST CDS_LIB pure_quanta
J 0
(-2850 5775);
DISPLAY INVISIBLE (-2850 5775);
FORCEPROP 2 LAST BOM_COST MEM
J 0
(-2800 5950);
DISPLAY 0.808511 (-2800 5950);
DISPLAY INVISIBLE (-2800 5950);
FORCEPROP 1 LAST PATH I708
J 0
(-2800 5950);
DISPLAY 0.978723 (-2800 5950);
PAINT WHITE (-2800 5950);
DISPLAY INVISIBLE (-2800 5950);
FORCEPROP 1 LAST PART_NUMBER CS31002FB08
J 0
(-2810 5650);
DISPLAY 0.489362 (-2810 5650);
PAINT SKYBLUE (-2810 5650);
DISPLAY INVISIBLE (-2810 5650);
FORCEPROP 2 LAST ROOM MEM_CH_A_CPU0_DIMM1
J 0
(-2800 6000);
DISPLAY 0.808511 (-2800 6000);
PAINT RED (-2800 6000);
DISPLAY INVISIBLE (-2800 6000);
FORCEADD GND..1
(-2850 5550);
FORCEPROP 3 LASTPIN (-2850 5600) SIG_NAME GND\g
J 0
(-2840 5610);
DISPLAY 0.659574 (-2840 5610);
PAINT MONO (-2840 5610);
DISPLAY INVISIBLE (-2840 5610);
FORCEPROP 2 LAST BOM_COST MEM
J 0
(-2950 5625);
DISPLAY 0.808511 (-2950 5625);
DISPLAY INVISIBLE (-2950 5625);
FORCEPROP 1 LAST SIZE 1B
J 0
(-2775 5500);
DISPLAY 0.851064 (-2775 5500);
PAINT GREEN (-2775 5500);
DISPLAY INVISIBLE (-2775 5500);
FORCEPROP 2 LAST CDS_LIB mstr_symbols
J 0
(-2850 5550);
DISPLAY INVISIBLE (-2850 5550);
FORCEPROP 1 LAST BODY_TYPE PLUMBING
J 0
(-2895 5507);
DISPLAY 0.340426 (-2895 5507);
PAINT GREEN (-2895 5507);
DISPLAY INVISIBLE (-2895 5507);
FORCEPROP 1 LAST PATH I709
J 0
(-2775 5550);
DISPLAY 0.872340 (-2775 5550);
PAINT AQUA (-2775 5550);
DISPLAY INVISIBLE (-2775 5550);
FORCEPROP 1 LAST VOLTAGE 0.0
J 0
(-2895 5507);
DISPLAY 0.723404 (-2895 5507);
PAINT SKYBLUE (-2895 5507);
DISPLAY INVISIBLE (-2895 5507);
FORCEPROP 1 LAST HDL_POWER GND
J 0
(-2850 5700);
DISPLAY 0.851064 (-2850 5700);
PAINT GREEN (-2850 5700);
DISPLAY INVISIBLE (-2850 5700);
FORCEADD Q_RES..2
(-2325 4450);
FORCEPROP 1 LAST LOCATION R810
J 0
(-2280 4575);
DISPLAY 0.489362 (-2280 4575);
PAINT SKYBLUE (-2280 4575);
FORCEPROP 2 LAST $SEC 1
J 0
(-2275 4675);
DISPLAY 0.680851 (-2275 4675);
PAINT MONO (-2275 4675);
DISPLAY INVISIBLE (-2275 4675);
FORCEPROP 2 LAST CDS_SEC 1
J 0
(-2275 4675);
DISPLAY 1.021277 (-2275 4675);
DISPLAY INVISIBLE (-2275 4675);
FORCEPROP 1 LASTPIN (-2325 4550) $PN 1
J 0
(-2320 4512);
DISPLAY 0.489362 (-2320 4512);
PAINT MONO (-2320 4512);
FORCEPROP 1 LASTPIN (-2325 4350) $PN 2
J 0
(-2320 4360);
DISPLAY 0.489362 (-2320 4360);
PAINT MONO (-2320 4360);
FORCEPROP 1 LAST WATTAGE 1/16W
J 0
(-2300 4425);
DISPLAY 0.489362 (-2300 4425);
PAINT SKYBLUE (-2300 4425);
FORCEPROP 1 LAST MATERIAL CHIP
J 0
(-2300 4375);
DISPLAY 0.489362 (-2300 4375);
PAINT SKYBLUE (-2300 4375);
FORCEPROP 1 LAST TOLERANCE 1%
J 0
(-2300 4475);
DISPLAY 0.489362 (-2300 4475);
PAINT SKYBLUE (-2300 4475);
FORCEPROP 1 LAST VALUE 10K
J 0
(-2300 4525);
DISPLAY 0.489362 (-2300 4525);
PAINT SKYBLUE (-2300 4525);
FORCEPROP 1 LAST PACK_TYPE 0402LF
J 0
(-2300 4325);
DISPLAY 0.489362 (-2300 4325);
PAINT SKYBLUE (-2300 4325);
FORCEPROP 2 LAST BOM_COST MEM
J 0
(-2275 4625);
DISPLAY 0.808511 (-2275 4625);
DISPLAY INVISIBLE (-2275 4625);
FORCEPROP 2 LAST CDS_LIB pure_quanta
J 0
(-2325 4450);
DISPLAY INVISIBLE (-2325 4450);
FORCEPROP 1 LAST PATH I710
J 0
(-2275 4625);
DISPLAY 0.978723 (-2275 4625);
PAINT WHITE (-2275 4625);
DISPLAY INVISIBLE (-2275 4625);
FORCEPROP 1 LAST PART_NUMBER CS31002FB08
J 0
(-2285 4325);
DISPLAY 0.489362 (-2285 4325);
PAINT SKYBLUE (-2285 4325);
DISPLAY INVISIBLE (-2285 4325);
FORCEPROP 2 LAST ROOM MEM_CH_A_CPU0_DIMM1
J 0
(-2275 4675);
DISPLAY 0.808511 (-2275 4675);
PAINT RED (-2275 4675);
DISPLAY INVISIBLE (-2275 4675);
FORCEADD Q_RES..2
(-2450 4450);
FORCEPROP 1 LAST LOCATION R809
J 0
(-2405 4575);
DISPLAY 0.489362 (-2405 4575);
PAINT SKYBLUE (-2405 4575);
FORCEPROP 2 LAST $SEC 1
J 0
(-2400 4675);
DISPLAY 0.680851 (-2400 4675);
PAINT MONO (-2400 4675);
DISPLAY INVISIBLE (-2400 4675);
FORCEPROP 2 LAST CDS_SEC 1
J 0
(-2400 4675);
DISPLAY 1.021277 (-2400 4675);
DISPLAY INVISIBLE (-2400 4675);
FORCEPROP 1 LASTPIN (-2450 4550) $PN 1
J 0
(-2445 4512);
DISPLAY 0.489362 (-2445 4512);
PAINT MONO (-2445 4512);
FORCEPROP 1 LASTPIN (-2450 4350) $PN 2
J 0
(-2445 4360);
DISPLAY 0.489362 (-2445 4360);
PAINT MONO (-2445 4360);
FORCEPROP 1 LAST WATTAGE 1/16W
J 0
(-2425 4425);
DISPLAY 0.489362 (-2425 4425);
PAINT SKYBLUE (-2425 4425);
FORCEPROP 1 LAST MATERIAL CHIP
J 0
(-2425 4375);
DISPLAY 0.489362 (-2425 4375);
PAINT SKYBLUE (-2425 4375);
FORCEPROP 1 LAST TOLERANCE 1%
J 0
(-2425 4475);
DISPLAY 0.489362 (-2425 4475);
PAINT SKYBLUE (-2425 4475);
FORCEPROP 1 LAST VALUE 10K
J 0
(-2425 4525);
DISPLAY 0.489362 (-2425 4525);
PAINT SKYBLUE (-2425 4525);
FORCEPROP 1 LAST PACK_TYPE 0402LF
J 0
(-2425 4325);
DISPLAY 0.489362 (-2425 4325);
PAINT SKYBLUE (-2425 4325);
FORCEPROP 2 LAST BOM_COST MEM
J 0
(-2400 4625);
DISPLAY 0.808511 (-2400 4625);
DISPLAY INVISIBLE (-2400 4625);
FORCEPROP 2 LAST CDS_LIB pure_quanta
J 0
(-2450 4450);
DISPLAY INVISIBLE (-2450 4450);
FORCEPROP 1 LAST PATH I711
J 0
(-2400 4625);
DISPLAY 0.978723 (-2400 4625);
PAINT WHITE (-2400 4625);
DISPLAY INVISIBLE (-2400 4625);
FORCEPROP 1 LAST PART_NUMBER CS31002FB08
J 0
(-2410 4325);
DISPLAY 0.489362 (-2410 4325);
PAINT SKYBLUE (-2410 4325);
DISPLAY INVISIBLE (-2410 4325);
FORCEPROP 2 LAST ROOM MEM_CH_A_CPU0_DIMM1
J 0
(-2400 4675);
DISPLAY 0.808511 (-2400 4675);
PAINT RED (-2400 4675);
DISPLAY INVISIBLE (-2400 4675);
FORCEADD Q_RES..2
(-2575 4450);
FORCEPROP 1 LAST LOCATION R808
J 0
(-2530 4575);
DISPLAY 0.489362 (-2530 4575);
PAINT SKYBLUE (-2530 4575);
FORCEPROP 2 LAST $SEC 1
J 0
(-2525 4675);
DISPLAY 0.680851 (-2525 4675);
PAINT MONO (-2525 4675);
DISPLAY INVISIBLE (-2525 4675);
FORCEPROP 2 LAST CDS_SEC 1
J 0
(-2525 4675);
DISPLAY 1.021277 (-2525 4675);
DISPLAY INVISIBLE (-2525 4675);
FORCEPROP 1 LASTPIN (-2575 4550) $PN 1
J 0
(-2570 4512);
DISPLAY 0.489362 (-2570 4512);
PAINT MONO (-2570 4512);
FORCEPROP 1 LASTPIN (-2575 4350) $PN 2
J 0
(-2570 4360);
DISPLAY 0.489362 (-2570 4360);
PAINT MONO (-2570 4360);
FORCEPROP 1 LAST WATTAGE 1/16W
J 0
(-2550 4425);
DISPLAY 0.489362 (-2550 4425);
PAINT SKYBLUE (-2550 4425);
FORCEPROP 1 LAST MATERIAL CHIP
J 0
(-2550 4375);
DISPLAY 0.489362 (-2550 4375);
PAINT SKYBLUE (-2550 4375);
FORCEPROP 1 LAST TOLERANCE 1%
J 0
(-2550 4475);
DISPLAY 0.489362 (-2550 4475);
PAINT SKYBLUE (-2550 4475);
FORCEPROP 1 LAST VALUE 10K
J 0
(-2550 4525);
DISPLAY 0.489362 (-2550 4525);
PAINT SKYBLUE (-2550 4525);
FORCEPROP 1 LAST PACK_TYPE 0402LF
J 0
(-2550 4325);
DISPLAY 0.489362 (-2550 4325);
PAINT SKYBLUE (-2550 4325);
FORCEPROP 2 LAST BOM_COST MEM
J 0
(-2525 4625);
DISPLAY 0.808511 (-2525 4625);
DISPLAY INVISIBLE (-2525 4625);
FORCEPROP 2 LAST CDS_LIB pure_quanta
J 0
(-2575 4450);
DISPLAY INVISIBLE (-2575 4450);
FORCEPROP 1 LAST PATH I712
J 0
(-2525 4625);
DISPLAY 0.978723 (-2525 4625);
PAINT WHITE (-2525 4625);
DISPLAY INVISIBLE (-2525 4625);
FORCEPROP 1 LAST PART_NUMBER CS31002FB08
J 0
(-2535 4325);
DISPLAY 0.489362 (-2535 4325);
PAINT SKYBLUE (-2535 4325);
DISPLAY INVISIBLE (-2535 4325);
FORCEPROP 2 LAST ROOM MEM_CH_A_CPU0_DIMM1
J 0
(-2525 4675);
DISPLAY 0.808511 (-2525 4675);
PAINT RED (-2525 4675);
DISPLAY INVISIBLE (-2525 4675);
FORCEADD Q_RES..2
(-2700 4450);
FORCEPROP 1 LAST LOCATION R807
J 0
(-2655 4575);
DISPLAY 0.489362 (-2655 4575);
PAINT SKYBLUE (-2655 4575);
FORCEPROP 2 LAST $SEC 1
J 0
(-2650 4675);
DISPLAY 0.680851 (-2650 4675);
PAINT MONO (-2650 4675);
DISPLAY INVISIBLE (-2650 4675);
FORCEPROP 2 LAST CDS_SEC 1
J 0
(-2650 4675);
DISPLAY 1.021277 (-2650 4675);
DISPLAY INVISIBLE (-2650 4675);
FORCEPROP 1 LASTPIN (-2700 4550) $PN 1
J 0
(-2695 4512);
DISPLAY 0.489362 (-2695 4512);
PAINT MONO (-2695 4512);
FORCEPROP 1 LASTPIN (-2700 4350) $PN 2
J 0
(-2695 4360);
DISPLAY 0.489362 (-2695 4360);
PAINT MONO (-2695 4360);
FORCEPROP 1 LAST WATTAGE 1/16W
J 0
(-2675 4425);
DISPLAY 0.489362 (-2675 4425);
PAINT SKYBLUE (-2675 4425);
FORCEPROP 1 LAST MATERIAL CHIP
J 0
(-2675 4375);
DISPLAY 0.489362 (-2675 4375);
PAINT SKYBLUE (-2675 4375);
FORCEPROP 1 LAST TOLERANCE 1%
J 0
(-2675 4475);
DISPLAY 0.489362 (-2675 4475);
PAINT SKYBLUE (-2675 4475);
FORCEPROP 1 LAST VALUE 10K
J 0
(-2675 4525);
DISPLAY 0.489362 (-2675 4525);
PAINT SKYBLUE (-2675 4525);
FORCEPROP 1 LAST PACK_TYPE 0402LF
J 0
(-2675 4325);
DISPLAY 0.489362 (-2675 4325);
PAINT SKYBLUE (-2675 4325);
FORCEPROP 2 LAST BOM_COST MEM
J 0
(-2650 4625);
DISPLAY 0.808511 (-2650 4625);
DISPLAY INVISIBLE (-2650 4625);
FORCEPROP 2 LAST CDS_LIB pure_quanta
J 0
(-2700 4450);
DISPLAY INVISIBLE (-2700 4450);
FORCEPROP 1 LAST PATH I713
J 0
(-2650 4625);
DISPLAY 0.978723 (-2650 4625);
PAINT WHITE (-2650 4625);
DISPLAY INVISIBLE (-2650 4625);
FORCEPROP 1 LAST PART_NUMBER CS31002FB08
J 0
(-2660 4325);
DISPLAY 0.489362 (-2660 4325);
PAINT SKYBLUE (-2660 4325);
DISPLAY INVISIBLE (-2660 4325);
FORCEPROP 2 LAST ROOM MEM_CH_A_CPU0_DIMM1
J 0
(-2650 4675);
DISPLAY 0.808511 (-2650 4675);
PAINT RED (-2650 4675);
DISPLAY INVISIBLE (-2650 4675);
FORCEADD Q_RES..2
(-2825 4450);
FORCEPROP 1 LAST LOCATION R806
J 0
(-2780 4575);
DISPLAY 0.489362 (-2780 4575);
PAINT SKYBLUE (-2780 4575);
FORCEPROP 2 LAST $SEC 1
J 0
(-2775 4675);
DISPLAY 0.680851 (-2775 4675);
PAINT MONO (-2775 4675);
DISPLAY INVISIBLE (-2775 4675);
FORCEPROP 2 LAST CDS_SEC 1
J 0
(-2775 4675);
DISPLAY 1.021277 (-2775 4675);
DISPLAY INVISIBLE (-2775 4675);
FORCEPROP 1 LASTPIN (-2825 4550) $PN 1
J 0
(-2820 4512);
DISPLAY 0.489362 (-2820 4512);
PAINT MONO (-2820 4512);
FORCEPROP 1 LASTPIN (-2825 4350) $PN 2
J 0
(-2820 4360);
DISPLAY 0.489362 (-2820 4360);
PAINT MONO (-2820 4360);
FORCEPROP 1 LAST WATTAGE 1/16W
J 0
(-2800 4425);
DISPLAY 0.489362 (-2800 4425);
PAINT SKYBLUE (-2800 4425);
FORCEPROP 1 LAST MATERIAL CHIP
J 0
(-2800 4375);
DISPLAY 0.489362 (-2800 4375);
PAINT SKYBLUE (-2800 4375);
FORCEPROP 1 LAST TOLERANCE 1%
J 0
(-2800 4475);
DISPLAY 0.489362 (-2800 4475);
PAINT SKYBLUE (-2800 4475);
FORCEPROP 1 LAST VALUE 10K
J 0
(-2800 4525);
DISPLAY 0.489362 (-2800 4525);
PAINT SKYBLUE (-2800 4525);
FORCEPROP 1 LAST PACK_TYPE 0402LF
J 0
(-2800 4325);
DISPLAY 0.489362 (-2800 4325);
PAINT SKYBLUE (-2800 4325);
FORCEPROP 2 LAST BOM_COST MEM
J 0
(-2775 4625);
DISPLAY 0.808511 (-2775 4625);
DISPLAY INVISIBLE (-2775 4625);
FORCEPROP 2 LAST CDS_LIB pure_quanta
J 0
(-2825 4450);
DISPLAY INVISIBLE (-2825 4450);
FORCEPROP 1 LAST PATH I714
J 0
(-2775 4625);
DISPLAY 0.978723 (-2775 4625);
PAINT WHITE (-2775 4625);
DISPLAY INVISIBLE (-2775 4625);
FORCEPROP 1 LAST PART_NUMBER CS31002FB08
J 0
(-2785 4325);
DISPLAY 0.489362 (-2785 4325);
PAINT SKYBLUE (-2785 4325);
DISPLAY INVISIBLE (-2785 4325);
FORCEPROP 2 LAST ROOM MEM_CH_A_CPU0_DIMM1
J 0
(-2775 4675);
DISPLAY 0.808511 (-2775 4675);
PAINT RED (-2775 4675);
DISPLAY INVISIBLE (-2775 4675);
FORCEADD Q_RES..2
(-2975 4450);
FORCEPROP 1 LAST LOCATION R805
J 0
(-2930 4575);
DISPLAY 0.489362 (-2930 4575);
PAINT SKYBLUE (-2930 4575);
FORCEPROP 2 LAST $SEC 1
J 0
(-2925 4675);
DISPLAY 0.680851 (-2925 4675);
PAINT MONO (-2925 4675);
DISPLAY INVISIBLE (-2925 4675);
FORCEPROP 2 LAST CDS_SEC 1
J 0
(-2925 4675);
DISPLAY 1.021277 (-2925 4675);
DISPLAY INVISIBLE (-2925 4675);
FORCEPROP 1 LASTPIN (-2975 4550) $PN 1
J 0
(-2970 4512);
DISPLAY 0.489362 (-2970 4512);
PAINT MONO (-2970 4512);
FORCEPROP 1 LASTPIN (-2975 4350) $PN 2
J 0
(-2970 4360);
DISPLAY 0.489362 (-2970 4360);
PAINT MONO (-2970 4360);
FORCEPROP 1 LAST WATTAGE 1/16W
J 0
(-2950 4425);
DISPLAY 0.489362 (-2950 4425);
PAINT SKYBLUE (-2950 4425);
FORCEPROP 1 LAST MATERIAL CHIP
J 0
(-2950 4375);
DISPLAY 0.489362 (-2950 4375);
PAINT SKYBLUE (-2950 4375);
FORCEPROP 1 LAST TOLERANCE 1%
J 0
(-2950 4475);
DISPLAY 0.489362 (-2950 4475);
PAINT SKYBLUE (-2950 4475);
FORCEPROP 1 LAST VALUE 10K
J 0
(-2950 4525);
DISPLAY 0.489362 (-2950 4525);
PAINT SKYBLUE (-2950 4525);
FORCEPROP 1 LAST PACK_TYPE 0402LF
J 0
(-2950 4325);
DISPLAY 0.489362 (-2950 4325);
PAINT SKYBLUE (-2950 4325);
FORCEPROP 2 LAST CDS_LIB pure_quanta
J 0
(-2975 4450);
DISPLAY INVISIBLE (-2975 4450);
FORCEPROP 2 LAST BOM_COST MEM
J 0
(-2925 4625);
DISPLAY 0.808511 (-2925 4625);
DISPLAY INVISIBLE (-2925 4625);
FORCEPROP 1 LAST PATH I715
J 0
(-2925 4625);
DISPLAY 0.978723 (-2925 4625);
PAINT WHITE (-2925 4625);
DISPLAY INVISIBLE (-2925 4625);
FORCEPROP 1 LAST PART_NUMBER CS31002FB08
J 0
(-2935 4325);
DISPLAY 0.489362 (-2935 4325);
PAINT SKYBLUE (-2935 4325);
DISPLAY INVISIBLE (-2935 4325);
FORCEPROP 2 LAST ROOM MEM_CH_A_CPU0_DIMM1
J 0
(-2925 4675);
DISPLAY 0.808511 (-2925 4675);
PAINT RED (-2925 4675);
DISPLAY INVISIBLE (-2925 4675);
FORCEADD GND..1
(-2325 4225);
FORCEPROP 3 LASTPIN (-2325 4275) SIG_NAME GND\g
J 0
(-2315 4285);
DISPLAY 0.659574 (-2315 4285);
PAINT MONO (-2315 4285);
DISPLAY INVISIBLE (-2315 4285);
FORCEPROP 2 LAST CDS_LIB mstr_symbols
J 0
(-2325 4225);
DISPLAY INVISIBLE (-2325 4225);
FORCEPROP 1 LAST SIZE 1B
J 0
(-2250 4175);
DISPLAY 0.851064 (-2250 4175);
PAINT GREEN (-2250 4175);
DISPLAY INVISIBLE (-2250 4175);
FORCEPROP 2 LAST BOM_COST MEM
J 0
(-2425 4300);
DISPLAY 0.808511 (-2425 4300);
DISPLAY INVISIBLE (-2425 4300);
FORCEPROP 1 LAST BODY_TYPE PLUMBING
J 0
(-2370 4182);
DISPLAY 0.340426 (-2370 4182);
PAINT GREEN (-2370 4182);
DISPLAY INVISIBLE (-2370 4182);
FORCEPROP 1 LAST PATH I716
J 0
(-2250 4225);
DISPLAY 0.872340 (-2250 4225);
PAINT AQUA (-2250 4225);
DISPLAY INVISIBLE (-2250 4225);
FORCEPROP 1 LAST VOLTAGE 0.0
J 0
(-2370 4182);
DISPLAY 0.723404 (-2370 4182);
PAINT SKYBLUE (-2370 4182);
DISPLAY INVISIBLE (-2370 4182);
FORCEPROP 1 LAST HDL_POWER GND
J 0
(-2325 4375);
DISPLAY 0.851064 (-2325 4375);
PAINT GREEN (-2325 4375);
DISPLAY INVISIBLE (-2325 4375);
FORCEADD GND..1
(-2450 4225);
FORCEPROP 3 LASTPIN (-2450 4275) SIG_NAME GND\g
J 0
(-2440 4285);
DISPLAY 0.659574 (-2440 4285);
PAINT MONO (-2440 4285);
DISPLAY INVISIBLE (-2440 4285);
FORCEPROP 2 LAST CDS_LIB mstr_symbols
J 0
(-2450 4225);
DISPLAY INVISIBLE (-2450 4225);
FORCEPROP 1 LAST SIZE 1B
J 0
(-2375 4175);
DISPLAY 0.851064 (-2375 4175);
PAINT GREEN (-2375 4175);
DISPLAY INVISIBLE (-2375 4175);
FORCEPROP 2 LAST BOM_COST MEM
J 0
(-2550 4300);
DISPLAY 0.808511 (-2550 4300);
DISPLAY INVISIBLE (-2550 4300);
FORCEPROP 1 LAST BODY_TYPE PLUMBING
J 0
(-2495 4182);
DISPLAY 0.340426 (-2495 4182);
PAINT GREEN (-2495 4182);
DISPLAY INVISIBLE (-2495 4182);
FORCEPROP 1 LAST PATH I717
J 0
(-2375 4225);
DISPLAY 0.872340 (-2375 4225);
PAINT AQUA (-2375 4225);
DISPLAY INVISIBLE (-2375 4225);
FORCEPROP 1 LAST VOLTAGE 0.0
J 0
(-2495 4182);
DISPLAY 0.723404 (-2495 4182);
PAINT SKYBLUE (-2495 4182);
DISPLAY INVISIBLE (-2495 4182);
FORCEPROP 1 LAST HDL_POWER GND
J 0
(-2450 4375);
DISPLAY 0.851064 (-2450 4375);
PAINT GREEN (-2450 4375);
DISPLAY INVISIBLE (-2450 4375);
FORCEADD GND..1
(-2575 4225);
FORCEPROP 3 LASTPIN (-2575 4275) SIG_NAME GND\g
J 0
(-2565 4285);
DISPLAY 0.659574 (-2565 4285);
PAINT MONO (-2565 4285);
DISPLAY INVISIBLE (-2565 4285);
FORCEPROP 2 LAST CDS_LIB pure_quanta_power
J 0
(-2575 4225);
DISPLAY INVISIBLE (-2575 4225);
FORCEPROP 1 LAST SIZE 1B
J 0
(-2500 4175);
DISPLAY 0.851064 (-2500 4175);
PAINT GREEN (-2500 4175);
DISPLAY INVISIBLE (-2500 4175);
FORCEPROP 2 LAST BOM_COST MEM
J 0
(-2675 4300);
DISPLAY 0.808511 (-2675 4300);
DISPLAY INVISIBLE (-2675 4300);
FORCEPROP 1 LAST PATH I718
J 0
(-2500 4225);
DISPLAY 0.872340 (-2500 4225);
PAINT AQUA (-2500 4225);
DISPLAY INVISIBLE (-2500 4225);
FORCEPROP 1 LAST HDL_POWER GND
J 0
(-2575 4375);
DISPLAY 0.851064 (-2575 4375);
PAINT GREEN (-2575 4375);
DISPLAY INVISIBLE (-2575 4375);
FORCEADD GND..1
(-2700 4225);
FORCEPROP 3 LASTPIN (-2700 4275) SIG_NAME GND\g
J 0
(-2690 4285);
DISPLAY 0.659574 (-2690 4285);
PAINT MONO (-2690 4285);
DISPLAY INVISIBLE (-2690 4285);
FORCEPROP 2 LAST CDS_LIB pure_quanta_power
J 0
(-2700 4225);
DISPLAY INVISIBLE (-2700 4225);
FORCEPROP 2 LAST BOM_COST MEM
J 0
(-2800 4300);
DISPLAY 0.808511 (-2800 4300);
DISPLAY INVISIBLE (-2800 4300);
FORCEPROP 1 LAST SIZE 1B
J 0
(-2625 4175);
DISPLAY 0.851064 (-2625 4175);
PAINT GREEN (-2625 4175);
DISPLAY INVISIBLE (-2625 4175);
FORCEPROP 1 LAST PATH I719
J 0
(-2625 4225);
DISPLAY 0.872340 (-2625 4225);
PAINT AQUA (-2625 4225);
DISPLAY INVISIBLE (-2625 4225);
FORCEPROP 1 LAST HDL_POWER GND
J 0
(-2700 4375);
DISPLAY 0.851064 (-2700 4375);
PAINT GREEN (-2700 4375);
DISPLAY INVISIBLE (-2700 4375);
FORCEADD GND..1
(-2825 4225);
FORCEPROP 3 LASTPIN (-2825 4275) SIG_NAME GND\g
J 0
(-2815 4285);
DISPLAY 0.659574 (-2815 4285);
PAINT MONO (-2815 4285);
DISPLAY INVISIBLE (-2815 4285);
FORCEPROP 2 LAST CDS_LIB pure_quanta_power
J 0
(-2825 4225);
DISPLAY INVISIBLE (-2825 4225);
FORCEPROP 1 LAST SIZE 1B
J 0
(-2750 4175);
DISPLAY 0.851064 (-2750 4175);
PAINT GREEN (-2750 4175);
DISPLAY INVISIBLE (-2750 4175);
FORCEPROP 2 LAST BOM_COST MEM
J 0
(-2925 4300);
DISPLAY 0.808511 (-2925 4300);
DISPLAY INVISIBLE (-2925 4300);
FORCEPROP 1 LAST PATH I720
J 0
(-2750 4225);
DISPLAY 0.872340 (-2750 4225);
PAINT AQUA (-2750 4225);
DISPLAY INVISIBLE (-2750 4225);
FORCEPROP 1 LAST HDL_POWER GND
J 0
(-2825 4375);
DISPLAY 0.851064 (-2825 4375);
PAINT GREEN (-2825 4375);
DISPLAY INVISIBLE (-2825 4375);
FORCEADD GND..1
(-2975 4225);
FORCEPROP 3 LASTPIN (-2975 4275) SIG_NAME GND\g
J 0
(-2965 4285);
DISPLAY 0.659574 (-2965 4285);
PAINT MONO (-2965 4285);
DISPLAY INVISIBLE (-2965 4285);
FORCEPROP 2 LAST BOM_COST MEM
J 0
(-3075 4300);
DISPLAY 0.808511 (-3075 4300);
DISPLAY INVISIBLE (-3075 4300);
FORCEPROP 1 LAST SIZE 1B
J 0
(-2900 4175);
DISPLAY 0.851064 (-2900 4175);
PAINT GREEN (-2900 4175);
DISPLAY INVISIBLE (-2900 4175);
FORCEPROP 2 LAST CDS_LIB pure_quanta_power
J 0
(-2975 4225);
DISPLAY INVISIBLE (-2975 4225);
FORCEPROP 1 LAST PATH I721
J 0
(-2900 4225);
DISPLAY 0.872340 (-2900 4225);
PAINT AQUA (-2900 4225);
DISPLAY INVISIBLE (-2900 4225);
FORCEPROP 1 LAST HDL_POWER GND
J 0
(-2975 4375);
DISPLAY 0.851064 (-2975 4375);
PAINT GREEN (-2975 4375);
DISPLAY INVISIBLE (-2975 4375);
FORCEADD Q_RES..2
(-3075 5775);
FORCEPROP 1 LAST LOCATION R18
J 0
(-3050 5900);
DISPLAY 0.489362 (-3050 5900);
PAINT SKYBLUE (-3050 5900);
FORCEPROP 0 LAST $SEC 1
J 0
(-3025 5950);
DISPLAY 0.680851 (-3025 5950);
PAINT MONO (-3025 5950);
DISPLAY INVISIBLE (-3025 5950);
FORCEPROP 0 LAST CDS_SEC 1
J 0
(-3025 5950);
DISPLAY 1.021277 (-3025 5950);
DISPLAY INVISIBLE (-3025 5950);
FORCEPROP 1 LASTPIN (-3075 5875) $PN 1
J 0
(-3070 5837);
DISPLAY 0.489362 (-3070 5837);
PAINT MONO (-3070 5837);
FORCEPROP 1 LASTPIN (-3075 5675) $PN 2
J 0
(-3070 5685);
DISPLAY 0.489362 (-3070 5685);
PAINT MONO (-3070 5685);
FORCEPROP 1 LAST WATTAGE 1/16W
J 0
(-3035 5750);
DISPLAY 0.489362 (-3035 5750);
PAINT SKYBLUE (-3035 5750);
FORCEPROP 1 LAST MATERIAL CHIP
J 0
(-3035 5700);
DISPLAY 0.489362 (-3035 5700);
PAINT SKYBLUE (-3035 5700);
FORCEPROP 1 LAST TOLERANCE 1%
J 0
(-3030 5800);
DISPLAY 0.489362 (-3030 5800);
PAINT SKYBLUE (-3030 5800);
FORCEPROP 1 LAST VALUE 10K
J 0
(-3030 5850);
DISPLAY 0.489362 (-3030 5850);
PAINT SKYBLUE (-3030 5850);
FORCEPROP 1 LAST PACK_TYPE 0402LF
J 0
(-3025 5650);
DISPLAY 0.489362 (-3025 5650);
PAINT SKYBLUE (-3025 5650);
FORCEPROP 2 LAST BOM_COST MEM
J 0
(-3025 5950);
DISPLAY 0.808511 (-3025 5950);
DISPLAY INVISIBLE (-3025 5950);
FORCEPROP 2 LAST CDS_LIB pure_quanta
J 0
(-3075 5775);
DISPLAY INVISIBLE (-3075 5775);
FORCEPROP 1 LAST PATH I722
J 0
(-3025 5950);
DISPLAY 0.978723 (-3025 5950);
PAINT WHITE (-3025 5950);
DISPLAY INVISIBLE (-3025 5950);
FORCEPROP 1 LAST PART_NUMBER CS31002FB08
J 0
(-3035 5650);
DISPLAY 0.489362 (-3035 5650);
PAINT SKYBLUE (-3035 5650);
DISPLAY INVISIBLE (-3035 5650);
FORCEPROP 2 LAST ROOM MEM_CH_A_CPU0_DIMM1
J 0
(-3025 6000);
DISPLAY 0.808511 (-3025 6000);
PAINT RED (-3025 6000);
DISPLAY INVISIBLE (-3025 6000);
FORCEADD Q_RES..2
(-3275 5775);
FORCEPROP 1 LAST LOCATION R17
J 0
(-3250 5900);
DISPLAY 0.489362 (-3250 5900);
PAINT SKYBLUE (-3250 5900);
FORCEPROP 0 LAST $SEC 1
J 0
(-3225 5950);
DISPLAY 0.680851 (-3225 5950);
PAINT MONO (-3225 5950);
DISPLAY INVISIBLE (-3225 5950);
FORCEPROP 0 LAST CDS_SEC 1
J 0
(-3225 5950);
DISPLAY 1.021277 (-3225 5950);
DISPLAY INVISIBLE (-3225 5950);
FORCEPROP 1 LASTPIN (-3275 5875) $PN 1
J 0
(-3270 5837);
DISPLAY 0.489362 (-3270 5837);
PAINT MONO (-3270 5837);
FORCEPROP 1 LASTPIN (-3275 5675) $PN 2
J 0
(-3270 5685);
DISPLAY 0.489362 (-3270 5685);
PAINT MONO (-3270 5685);
FORCEPROP 1 LAST WATTAGE 1/16W
J 0
(-3235 5750);
DISPLAY 0.489362 (-3235 5750);
PAINT SKYBLUE (-3235 5750);
FORCEPROP 1 LAST MATERIAL CHIP
J 0
(-3235 5700);
DISPLAY 0.489362 (-3235 5700);
PAINT SKYBLUE (-3235 5700);
FORCEPROP 1 LAST TOLERANCE 1%
J 0
(-3230 5800);
DISPLAY 0.489362 (-3230 5800);
PAINT SKYBLUE (-3230 5800);
FORCEPROP 1 LAST VALUE 10K
J 0
(-3230 5850);
DISPLAY 0.489362 (-3230 5850);
PAINT SKYBLUE (-3230 5850);
FORCEPROP 1 LAST PACK_TYPE 0402LF
J 0
(-3225 5650);
DISPLAY 0.489362 (-3225 5650);
PAINT SKYBLUE (-3225 5650);
FORCEPROP 2 LAST BOM_COST MEM
J 0
(-3225 5950);
DISPLAY 0.808511 (-3225 5950);
DISPLAY INVISIBLE (-3225 5950);
FORCEPROP 2 LAST CDS_LIB pure_quanta
J 0
(-3275 5775);
DISPLAY INVISIBLE (-3275 5775);
FORCEPROP 1 LAST PATH I723
J 0
(-3225 5950);
DISPLAY 0.978723 (-3225 5950);
PAINT WHITE (-3225 5950);
DISPLAY INVISIBLE (-3225 5950);
FORCEPROP 1 LAST PART_NUMBER CS31002FB08
J 0
(-3235 5650);
DISPLAY 0.489362 (-3235 5650);
PAINT SKYBLUE (-3235 5650);
DISPLAY INVISIBLE (-3235 5650);
FORCEPROP 2 LAST ROOM MEM_CH_A_CPU0_DIMM1
J 0
(-3225 6000);
DISPLAY 0.808511 (-3225 6000);
PAINT RED (-3225 6000);
DISPLAY INVISIBLE (-3225 6000);
FORCEADD GND..1
(-3075 5550);
FORCEPROP 3 LASTPIN (-3075 5600) SIG_NAME GND\g
J 0
(-3065 5610);
DISPLAY 0.659574 (-3065 5610);
PAINT MONO (-3065 5610);
DISPLAY INVISIBLE (-3065 5610);
FORCEPROP 2 LAST CDS_LIB mstr_symbols
J 0
(-3075 5550);
DISPLAY INVISIBLE (-3075 5550);
FORCEPROP 2 LAST BOM_COST MEM
J 0
(-3175 5625);
DISPLAY 0.808511 (-3175 5625);
DISPLAY INVISIBLE (-3175 5625);
FORCEPROP 1 LAST SIZE 1B
J 0
(-3000 5500);
DISPLAY 0.851064 (-3000 5500);
PAINT GREEN (-3000 5500);
DISPLAY INVISIBLE (-3000 5500);
FORCEPROP 1 LAST BODY_TYPE PLUMBING
J 0
(-3120 5507);
DISPLAY 0.340426 (-3120 5507);
PAINT GREEN (-3120 5507);
DISPLAY INVISIBLE (-3120 5507);
FORCEPROP 1 LAST PATH I724
J 0
(-3000 5550);
DISPLAY 0.872340 (-3000 5550);
PAINT AQUA (-3000 5550);
DISPLAY INVISIBLE (-3000 5550);
FORCEPROP 1 LAST VOLTAGE 0.0
J 0
(-3120 5507);
DISPLAY 0.723404 (-3120 5507);
PAINT SKYBLUE (-3120 5507);
DISPLAY INVISIBLE (-3120 5507);
FORCEPROP 1 LAST HDL_POWER GND
J 0
(-3075 5700);
DISPLAY 0.851064 (-3075 5700);
PAINT GREEN (-3075 5700);
DISPLAY INVISIBLE (-3075 5700);
FORCEADD GND..1
(-3275 5550);
FORCEPROP 3 LASTPIN (-3275 5600) SIG_NAME GND\g
J 0
(-3265 5610);
DISPLAY 0.659574 (-3265 5610);
PAINT MONO (-3265 5610);
DISPLAY INVISIBLE (-3265 5610);
FORCEPROP 2 LAST CDS_LIB pure_quanta_power
J 0
(-3275 5550);
DISPLAY INVISIBLE (-3275 5550);
FORCEPROP 1 LAST SIZE 1B
J 0
(-3200 5500);
DISPLAY 0.851064 (-3200 5500);
PAINT GREEN (-3200 5500);
DISPLAY INVISIBLE (-3200 5500);
FORCEPROP 2 LAST BOM_COST MEM
J 0
(-3375 5625);
DISPLAY 0.808511 (-3375 5625);
DISPLAY INVISIBLE (-3375 5625);
FORCEPROP 1 LAST PATH I725
J 0
(-3200 5550);
DISPLAY 0.872340 (-3200 5550);
PAINT AQUA (-3200 5550);
DISPLAY INVISIBLE (-3200 5550);
FORCEPROP 1 LAST HDL_POWER GND
J 0
(-3275 5700);
DISPLAY 0.851064 (-3275 5700);
PAINT GREEN (-3275 5700);
DISPLAY INVISIBLE (-3275 5700);
FORCEADD Q_RES..2
(-3475 5775);
FORCEPROP 1 LAST LOCATION R16
J 0
(-3450 5900);
DISPLAY 0.489362 (-3450 5900);
PAINT SKYBLUE (-3450 5900);
FORCEPROP 0 LAST $SEC 1
J 0
(-3425 5950);
DISPLAY 0.680851 (-3425 5950);
PAINT MONO (-3425 5950);
DISPLAY INVISIBLE (-3425 5950);
FORCEPROP 0 LAST CDS_SEC 1
J 0
(-3425 5950);
DISPLAY 1.021277 (-3425 5950);
DISPLAY INVISIBLE (-3425 5950);
FORCEPROP 1 LASTPIN (-3475 5875) $PN 1
J 0
(-3470 5837);
DISPLAY 0.489362 (-3470 5837);
PAINT MONO (-3470 5837);
FORCEPROP 1 LASTPIN (-3475 5675) $PN 2
J 0
(-3470 5685);
DISPLAY 0.489362 (-3470 5685);
PAINT MONO (-3470 5685);
FORCEPROP 1 LAST WATTAGE 1/16W
J 0
(-3435 5750);
DISPLAY 0.489362 (-3435 5750);
PAINT SKYBLUE (-3435 5750);
FORCEPROP 1 LAST MATERIAL CHIP
J 0
(-3435 5700);
DISPLAY 0.489362 (-3435 5700);
PAINT SKYBLUE (-3435 5700);
FORCEPROP 1 LAST TOLERANCE 1%
J 0
(-3430 5800);
DISPLAY 0.489362 (-3430 5800);
PAINT SKYBLUE (-3430 5800);
FORCEPROP 1 LAST VALUE 10K
J 0
(-3430 5850);
DISPLAY 0.489362 (-3430 5850);
PAINT SKYBLUE (-3430 5850);
FORCEPROP 1 LAST PACK_TYPE 0402LF
J 0
(-3425 5650);
DISPLAY 0.489362 (-3425 5650);
PAINT SKYBLUE (-3425 5650);
FORCEPROP 2 LAST BOM_COST MEM
J 0
(-3425 5950);
DISPLAY 0.808511 (-3425 5950);
DISPLAY INVISIBLE (-3425 5950);
FORCEPROP 2 LAST CDS_LIB pure_quanta
J 0
(-3475 5775);
DISPLAY INVISIBLE (-3475 5775);
FORCEPROP 1 LAST PATH I726
J 0
(-3425 5950);
DISPLAY 0.978723 (-3425 5950);
PAINT WHITE (-3425 5950);
DISPLAY INVISIBLE (-3425 5950);
FORCEPROP 1 LAST PART_NUMBER CS31002FB08
J 0
(-3435 5650);
DISPLAY 0.489362 (-3435 5650);
PAINT SKYBLUE (-3435 5650);
DISPLAY INVISIBLE (-3435 5650);
FORCEPROP 2 LAST ROOM MEM_CH_A_CPU0_DIMM1
J 0
(-3425 6000);
DISPLAY 0.808511 (-3425 6000);
PAINT RED (-3425 6000);
DISPLAY INVISIBLE (-3425 6000);
FORCEADD GND..1
(-3475 5550);
FORCEPROP 3 LASTPIN (-3475 5600) SIG_NAME GND\g
J 0
(-3465 5610);
DISPLAY 0.659574 (-3465 5610);
PAINT MONO (-3465 5610);
DISPLAY INVISIBLE (-3465 5610);
FORCEPROP 2 LAST CDS_LIB pure_quanta_power
J 0
(-3475 5550);
DISPLAY INVISIBLE (-3475 5550);
FORCEPROP 1 LAST SIZE 1B
J 0
(-3400 5500);
DISPLAY 0.851064 (-3400 5500);
PAINT GREEN (-3400 5500);
DISPLAY INVISIBLE (-3400 5500);
FORCEPROP 2 LAST BOM_COST MEM
J 0
(-3575 5625);
DISPLAY 0.808511 (-3575 5625);
DISPLAY INVISIBLE (-3575 5625);
FORCEPROP 1 LAST PATH I727
J 0
(-3400 5550);
DISPLAY 0.872340 (-3400 5550);
PAINT AQUA (-3400 5550);
DISPLAY INVISIBLE (-3400 5550);
FORCEPROP 1 LAST HDL_POWER GND
J 0
(-3475 5700);
DISPLAY 0.851064 (-3475 5700);
PAINT GREEN (-3475 5700);
DISPLAY INVISIBLE (-3475 5700);
FORCEADD Q_RES..2
(-3100 4450);
FORCEPROP 1 LAST LOCATION R804
J 0
(-3055 4575);
DISPLAY 0.489362 (-3055 4575);
PAINT SKYBLUE (-3055 4575);
FORCEPROP 2 LAST $SEC 1
J 0
(-3050 4675);
DISPLAY 0.680851 (-3050 4675);
PAINT MONO (-3050 4675);
DISPLAY INVISIBLE (-3050 4675);
FORCEPROP 2 LAST CDS_SEC 1
J 0
(-3050 4675);
DISPLAY 1.021277 (-3050 4675);
DISPLAY INVISIBLE (-3050 4675);
FORCEPROP 1 LASTPIN (-3100 4550) $PN 1
J 0
(-3095 4512);
DISPLAY 0.489362 (-3095 4512);
PAINT MONO (-3095 4512);
FORCEPROP 1 LASTPIN (-3100 4350) $PN 2
J 0
(-3095 4360);
DISPLAY 0.489362 (-3095 4360);
PAINT MONO (-3095 4360);
FORCEPROP 1 LAST WATTAGE 1/16W
J 0
(-3075 4425);
DISPLAY 0.489362 (-3075 4425);
PAINT SKYBLUE (-3075 4425);
FORCEPROP 1 LAST MATERIAL CHIP
J 0
(-3075 4375);
DISPLAY 0.489362 (-3075 4375);
PAINT SKYBLUE (-3075 4375);
FORCEPROP 1 LAST TOLERANCE 1%
J 0
(-3075 4475);
DISPLAY 0.489362 (-3075 4475);
PAINT SKYBLUE (-3075 4475);
FORCEPROP 1 LAST VALUE 10K
J 0
(-3075 4525);
DISPLAY 0.489362 (-3075 4525);
PAINT SKYBLUE (-3075 4525);
FORCEPROP 1 LAST PACK_TYPE 0402LF
J 0
(-3075 4325);
DISPLAY 0.489362 (-3075 4325);
PAINT SKYBLUE (-3075 4325);
FORCEPROP 2 LAST CDS_LIB pure_quanta
J 0
(-3100 4450);
DISPLAY INVISIBLE (-3100 4450);
FORCEPROP 2 LAST BOM_COST MEM
J 0
(-3050 4625);
DISPLAY 0.808511 (-3050 4625);
DISPLAY INVISIBLE (-3050 4625);
FORCEPROP 1 LAST PATH I728
J 0
(-3050 4625);
DISPLAY 0.978723 (-3050 4625);
PAINT WHITE (-3050 4625);
DISPLAY INVISIBLE (-3050 4625);
FORCEPROP 1 LAST PART_NUMBER CS31002FB08
J 0
(-3060 4325);
DISPLAY 0.489362 (-3060 4325);
PAINT SKYBLUE (-3060 4325);
DISPLAY INVISIBLE (-3060 4325);
FORCEPROP 2 LAST ROOM MEM_CH_A_CPU0_DIMM1
J 0
(-3050 4675);
DISPLAY 0.808511 (-3050 4675);
PAINT RED (-3050 4675);
DISPLAY INVISIBLE (-3050 4675);
FORCEADD Q_RES..2
(-3225 4450);
FORCEPROP 1 LAST LOCATION R803
J 0
(-3180 4575);
DISPLAY 0.489362 (-3180 4575);
PAINT SKYBLUE (-3180 4575);
FORCEPROP 2 LAST $SEC 1
J 0
(-3175 4675);
DISPLAY 0.680851 (-3175 4675);
PAINT MONO (-3175 4675);
DISPLAY INVISIBLE (-3175 4675);
FORCEPROP 2 LAST CDS_SEC 1
J 0
(-3175 4675);
DISPLAY 1.021277 (-3175 4675);
DISPLAY INVISIBLE (-3175 4675);
FORCEPROP 1 LASTPIN (-3225 4550) $PN 1
J 0
(-3220 4512);
DISPLAY 0.489362 (-3220 4512);
PAINT MONO (-3220 4512);
FORCEPROP 1 LASTPIN (-3225 4350) $PN 2
J 0
(-3220 4360);
DISPLAY 0.489362 (-3220 4360);
PAINT MONO (-3220 4360);
FORCEPROP 1 LAST WATTAGE 1/16W
J 0
(-3200 4425);
DISPLAY 0.489362 (-3200 4425);
PAINT SKYBLUE (-3200 4425);
FORCEPROP 1 LAST MATERIAL CHIP
J 0
(-3200 4375);
DISPLAY 0.489362 (-3200 4375);
PAINT SKYBLUE (-3200 4375);
FORCEPROP 1 LAST TOLERANCE 1%
J 0
(-3200 4475);
DISPLAY 0.489362 (-3200 4475);
PAINT SKYBLUE (-3200 4475);
FORCEPROP 1 LAST VALUE 10K
J 0
(-3200 4525);
DISPLAY 0.489362 (-3200 4525);
PAINT SKYBLUE (-3200 4525);
FORCEPROP 1 LAST PACK_TYPE 0402LF
J 0
(-3200 4325);
DISPLAY 0.489362 (-3200 4325);
PAINT SKYBLUE (-3200 4325);
FORCEPROP 2 LAST CDS_LIB pure_quanta
J 0
(-3225 4450);
DISPLAY INVISIBLE (-3225 4450);
FORCEPROP 2 LAST BOM_COST MEM
J 0
(-3175 4625);
DISPLAY 0.808511 (-3175 4625);
DISPLAY INVISIBLE (-3175 4625);
FORCEPROP 1 LAST PATH I729
J 0
(-3175 4625);
DISPLAY 0.978723 (-3175 4625);
PAINT WHITE (-3175 4625);
DISPLAY INVISIBLE (-3175 4625);
FORCEPROP 1 LAST PART_NUMBER CS31002FB08
J 0
(-3185 4325);
DISPLAY 0.489362 (-3185 4325);
PAINT SKYBLUE (-3185 4325);
DISPLAY INVISIBLE (-3185 4325);
FORCEPROP 2 LAST ROOM MEM_CH_A_CPU0_DIMM1
J 0
(-3175 4675);
DISPLAY 0.808511 (-3175 4675);
PAINT RED (-3175 4675);
DISPLAY INVISIBLE (-3175 4675);
FORCEADD Q_RES..2
(-3350 4450);
FORCEPROP 1 LAST LOCATION R802
J 0
(-3305 4575);
DISPLAY 0.489362 (-3305 4575);
PAINT SKYBLUE (-3305 4575);
FORCEPROP 2 LAST $SEC 1
J 0
(-3300 4675);
DISPLAY 0.680851 (-3300 4675);
PAINT MONO (-3300 4675);
DISPLAY INVISIBLE (-3300 4675);
FORCEPROP 2 LAST CDS_SEC 1
J 0
(-3300 4675);
DISPLAY 1.021277 (-3300 4675);
DISPLAY INVISIBLE (-3300 4675);
FORCEPROP 1 LASTPIN (-3350 4550) $PN 1
J 0
(-3345 4512);
DISPLAY 0.489362 (-3345 4512);
PAINT MONO (-3345 4512);
FORCEPROP 1 LASTPIN (-3350 4350) $PN 2
J 0
(-3345 4360);
DISPLAY 0.489362 (-3345 4360);
PAINT MONO (-3345 4360);
FORCEPROP 1 LAST WATTAGE 1/16W
J 0
(-3325 4425);
DISPLAY 0.489362 (-3325 4425);
PAINT SKYBLUE (-3325 4425);
FORCEPROP 1 LAST MATERIAL CHIP
J 0
(-3325 4375);
DISPLAY 0.489362 (-3325 4375);
PAINT SKYBLUE (-3325 4375);
FORCEPROP 1 LAST TOLERANCE 1%
J 0
(-3325 4475);
DISPLAY 0.489362 (-3325 4475);
PAINT SKYBLUE (-3325 4475);
FORCEPROP 1 LAST VALUE 10K
J 0
(-3325 4525);
DISPLAY 0.489362 (-3325 4525);
PAINT SKYBLUE (-3325 4525);
FORCEPROP 1 LAST PACK_TYPE 0402LF
J 0
(-3325 4325);
DISPLAY 0.489362 (-3325 4325);
PAINT SKYBLUE (-3325 4325);
FORCEPROP 2 LAST CDS_LIB pure_quanta
J 0
(-3350 4450);
DISPLAY INVISIBLE (-3350 4450);
FORCEPROP 2 LAST BOM_COST MEM
J 0
(-3300 4625);
DISPLAY 0.808511 (-3300 4625);
DISPLAY INVISIBLE (-3300 4625);
FORCEPROP 1 LAST PATH I730
J 0
(-3300 4625);
DISPLAY 0.978723 (-3300 4625);
PAINT WHITE (-3300 4625);
DISPLAY INVISIBLE (-3300 4625);
FORCEPROP 1 LAST PART_NUMBER CS31002FB08
J 0
(-3310 4325);
DISPLAY 0.489362 (-3310 4325);
PAINT SKYBLUE (-3310 4325);
DISPLAY INVISIBLE (-3310 4325);
FORCEPROP 2 LAST ROOM MEM_CH_A_CPU0_DIMM1
J 0
(-3300 4675);
DISPLAY 0.808511 (-3300 4675);
PAINT RED (-3300 4675);
DISPLAY INVISIBLE (-3300 4675);
FORCEADD Q_RES..2
(-3475 4450);
FORCEPROP 1 LAST LOCATION R801
J 0
(-3430 4575);
DISPLAY 0.489362 (-3430 4575);
PAINT SKYBLUE (-3430 4575);
FORCEPROP 2 LAST $SEC 1
J 0
(-3425 4675);
DISPLAY 0.680851 (-3425 4675);
PAINT MONO (-3425 4675);
DISPLAY INVISIBLE (-3425 4675);
FORCEPROP 2 LAST CDS_SEC 1
J 0
(-3425 4675);
DISPLAY 1.021277 (-3425 4675);
DISPLAY INVISIBLE (-3425 4675);
FORCEPROP 1 LASTPIN (-3475 4550) $PN 1
J 0
(-3470 4512);
DISPLAY 0.489362 (-3470 4512);
PAINT MONO (-3470 4512);
FORCEPROP 1 LASTPIN (-3475 4350) $PN 2
J 0
(-3470 4360);
DISPLAY 0.489362 (-3470 4360);
PAINT MONO (-3470 4360);
FORCEPROP 1 LAST WATTAGE 1/16W
J 0
(-3450 4425);
DISPLAY 0.489362 (-3450 4425);
PAINT SKYBLUE (-3450 4425);
FORCEPROP 1 LAST MATERIAL CHIP
J 0
(-3450 4375);
DISPLAY 0.489362 (-3450 4375);
PAINT SKYBLUE (-3450 4375);
FORCEPROP 1 LAST TOLERANCE 1%
J 0
(-3450 4475);
DISPLAY 0.489362 (-3450 4475);
PAINT SKYBLUE (-3450 4475);
FORCEPROP 1 LAST VALUE 10K
J 0
(-3450 4525);
DISPLAY 0.489362 (-3450 4525);
PAINT SKYBLUE (-3450 4525);
FORCEPROP 1 LAST PACK_TYPE 0402LF
J 0
(-3450 4325);
DISPLAY 0.489362 (-3450 4325);
PAINT SKYBLUE (-3450 4325);
FORCEPROP 2 LAST CDS_LIB pure_quanta
J 0
(-3475 4450);
DISPLAY INVISIBLE (-3475 4450);
FORCEPROP 2 LAST BOM_COST MEM
J 0
(-3425 4625);
DISPLAY 0.808511 (-3425 4625);
DISPLAY INVISIBLE (-3425 4625);
FORCEPROP 1 LAST PATH I731
J 0
(-3425 4625);
DISPLAY 0.978723 (-3425 4625);
PAINT WHITE (-3425 4625);
DISPLAY INVISIBLE (-3425 4625);
FORCEPROP 1 LAST PART_NUMBER CS31002FB08
J 0
(-3435 4325);
DISPLAY 0.489362 (-3435 4325);
PAINT SKYBLUE (-3435 4325);
DISPLAY INVISIBLE (-3435 4325);
FORCEPROP 2 LAST ROOM MEM_CH_A_CPU0_DIMM1
J 0
(-3425 4675);
DISPLAY 0.808511 (-3425 4675);
PAINT RED (-3425 4675);
DISPLAY INVISIBLE (-3425 4675);
FORCEADD Q_RES..2
(-3600 4450);
FORCEPROP 1 LAST LOCATION R800
J 0
(-3555 4575);
DISPLAY 0.489362 (-3555 4575);
PAINT SKYBLUE (-3555 4575);
FORCEPROP 2 LAST $SEC 1
J 0
(-3550 4675);
DISPLAY 0.680851 (-3550 4675);
PAINT MONO (-3550 4675);
DISPLAY INVISIBLE (-3550 4675);
FORCEPROP 2 LAST CDS_SEC 1
J 0
(-3550 4675);
DISPLAY 1.021277 (-3550 4675);
DISPLAY INVISIBLE (-3550 4675);
FORCEPROP 1 LASTPIN (-3600 4550) $PN 1
J 0
(-3595 4512);
DISPLAY 0.489362 (-3595 4512);
PAINT MONO (-3595 4512);
FORCEPROP 1 LASTPIN (-3600 4350) $PN 2
J 0
(-3595 4360);
DISPLAY 0.489362 (-3595 4360);
PAINT MONO (-3595 4360);
FORCEPROP 1 LAST WATTAGE 1/16W
J 0
(-3575 4425);
DISPLAY 0.489362 (-3575 4425);
PAINT SKYBLUE (-3575 4425);
FORCEPROP 1 LAST MATERIAL CHIP
J 0
(-3575 4375);
DISPLAY 0.489362 (-3575 4375);
PAINT SKYBLUE (-3575 4375);
FORCEPROP 1 LAST TOLERANCE 1%
J 0
(-3575 4475);
DISPLAY 0.489362 (-3575 4475);
PAINT SKYBLUE (-3575 4475);
FORCEPROP 1 LAST VALUE 10K
J 0
(-3575 4525);
DISPLAY 0.489362 (-3575 4525);
PAINT SKYBLUE (-3575 4525);
FORCEPROP 1 LAST PACK_TYPE 0402LF
J 0
(-3575 4325);
DISPLAY 0.489362 (-3575 4325);
PAINT SKYBLUE (-3575 4325);
FORCEPROP 2 LAST CDS_LIB pure_quanta
J 0
(-3600 4450);
DISPLAY INVISIBLE (-3600 4450);
FORCEPROP 2 LAST BOM_COST MEM
J 0
(-3550 4625);
DISPLAY 0.808511 (-3550 4625);
DISPLAY INVISIBLE (-3550 4625);
FORCEPROP 1 LAST PATH I732
J 0
(-3550 4625);
DISPLAY 0.978723 (-3550 4625);
PAINT WHITE (-3550 4625);
DISPLAY INVISIBLE (-3550 4625);
FORCEPROP 1 LAST PART_NUMBER CS31002FB08
J 0
(-3560 4325);
DISPLAY 0.489362 (-3560 4325);
PAINT SKYBLUE (-3560 4325);
DISPLAY INVISIBLE (-3560 4325);
FORCEPROP 2 LAST ROOM MEM_CH_A_CPU0_DIMM1
J 0
(-3550 4675);
DISPLAY 0.808511 (-3550 4675);
PAINT RED (-3550 4675);
DISPLAY INVISIBLE (-3550 4675);
FORCEADD GND..1
(-3100 4225);
FORCEPROP 3 LASTPIN (-3100 4275) SIG_NAME GND\g
J 0
(-3090 4285);
DISPLAY 0.659574 (-3090 4285);
PAINT MONO (-3090 4285);
DISPLAY INVISIBLE (-3090 4285);
FORCEPROP 2 LAST BOM_COST MEM
J 0
(-3200 4300);
DISPLAY 0.808511 (-3200 4300);
DISPLAY INVISIBLE (-3200 4300);
FORCEPROP 1 LAST SIZE 1B
J 0
(-3025 4175);
DISPLAY 0.851064 (-3025 4175);
PAINT GREEN (-3025 4175);
DISPLAY INVISIBLE (-3025 4175);
FORCEPROP 2 LAST CDS_LIB mstr_symbols
J 0
(-3100 4225);
DISPLAY INVISIBLE (-3100 4225);
FORCEPROP 1 LAST BODY_TYPE PLUMBING
J 0
(-3145 4182);
DISPLAY 0.340426 (-3145 4182);
PAINT GREEN (-3145 4182);
DISPLAY INVISIBLE (-3145 4182);
FORCEPROP 1 LAST PATH I733
J 0
(-3025 4225);
DISPLAY 0.872340 (-3025 4225);
PAINT AQUA (-3025 4225);
DISPLAY INVISIBLE (-3025 4225);
FORCEPROP 1 LAST VOLTAGE 0.0
J 0
(-3145 4182);
DISPLAY 0.723404 (-3145 4182);
PAINT SKYBLUE (-3145 4182);
DISPLAY INVISIBLE (-3145 4182);
FORCEPROP 1 LAST HDL_POWER GND
J 0
(-3100 4375);
DISPLAY 0.851064 (-3100 4375);
PAINT GREEN (-3100 4375);
DISPLAY INVISIBLE (-3100 4375);
FORCEADD GND..1
(-3225 4225);
FORCEPROP 3 LASTPIN (-3225 4275) SIG_NAME GND\g
J 0
(-3215 4285);
DISPLAY 0.659574 (-3215 4285);
PAINT MONO (-3215 4285);
DISPLAY INVISIBLE (-3215 4285);
FORCEPROP 2 LAST BOM_COST MEM
J 0
(-3325 4300);
DISPLAY 0.808511 (-3325 4300);
DISPLAY INVISIBLE (-3325 4300);
FORCEPROP 1 LAST SIZE 1B
J 0
(-3150 4175);
DISPLAY 0.851064 (-3150 4175);
PAINT GREEN (-3150 4175);
DISPLAY INVISIBLE (-3150 4175);
FORCEPROP 2 LAST CDS_LIB mstr_symbols
J 0
(-3225 4225);
DISPLAY INVISIBLE (-3225 4225);
FORCEPROP 1 LAST BODY_TYPE PLUMBING
J 0
(-3270 4182);
DISPLAY 0.340426 (-3270 4182);
PAINT GREEN (-3270 4182);
DISPLAY INVISIBLE (-3270 4182);
FORCEPROP 1 LAST PATH I734
J 0
(-3150 4225);
DISPLAY 0.872340 (-3150 4225);
PAINT AQUA (-3150 4225);
DISPLAY INVISIBLE (-3150 4225);
FORCEPROP 1 LAST VOLTAGE 0.0
J 0
(-3270 4182);
DISPLAY 0.723404 (-3270 4182);
PAINT SKYBLUE (-3270 4182);
DISPLAY INVISIBLE (-3270 4182);
FORCEPROP 1 LAST HDL_POWER GND
J 0
(-3225 4375);
DISPLAY 0.851064 (-3225 4375);
PAINT GREEN (-3225 4375);
DISPLAY INVISIBLE (-3225 4375);
FORCEADD GND..1
(-3475 4225);
FORCEPROP 3 LASTPIN (-3475 4275) SIG_NAME GND\g
J 0
(-3465 4285);
DISPLAY 0.659574 (-3465 4285);
PAINT MONO (-3465 4285);
DISPLAY INVISIBLE (-3465 4285);
FORCEPROP 1 LAST SIZE 1B
J 0
(-3400 4175);
DISPLAY 0.851064 (-3400 4175);
PAINT GREEN (-3400 4175);
DISPLAY INVISIBLE (-3400 4175);
FORCEPROP 2 LAST BOM_COST MEM
J 0
(-3575 4300);
DISPLAY 0.808511 (-3575 4300);
DISPLAY INVISIBLE (-3575 4300);
FORCEPROP 2 LAST CDS_LIB pure_quanta_power
J 0
(-3475 4225);
DISPLAY INVISIBLE (-3475 4225);
FORCEPROP 1 LAST PATH I735
J 0
(-3400 4225);
DISPLAY 0.872340 (-3400 4225);
PAINT AQUA (-3400 4225);
DISPLAY INVISIBLE (-3400 4225);
FORCEPROP 1 LAST HDL_POWER GND
J 0
(-3475 4375);
DISPLAY 0.851064 (-3475 4375);
PAINT GREEN (-3475 4375);
DISPLAY INVISIBLE (-3475 4375);
FORCEADD GND..1
(-3350 4225);
FORCEPROP 3 LASTPIN (-3350 4275) SIG_NAME GND\g
J 0
(-3340 4285);
DISPLAY 0.659574 (-3340 4285);
PAINT MONO (-3340 4285);
DISPLAY INVISIBLE (-3340 4285);
FORCEPROP 2 LAST BOM_COST MEM
J 0
(-3450 4300);
DISPLAY 0.808511 (-3450 4300);
DISPLAY INVISIBLE (-3450 4300);
FORCEPROP 1 LAST SIZE 1B
J 0
(-3275 4175);
DISPLAY 0.851064 (-3275 4175);
PAINT GREEN (-3275 4175);
DISPLAY INVISIBLE (-3275 4175);
FORCEPROP 2 LAST CDS_LIB pure_quanta_power
J 0
(-3350 4225);
DISPLAY INVISIBLE (-3350 4225);
FORCEPROP 1 LAST PATH I736
J 0
(-3275 4225);
DISPLAY 0.872340 (-3275 4225);
PAINT AQUA (-3275 4225);
DISPLAY INVISIBLE (-3275 4225);
FORCEPROP 1 LAST HDL_POWER GND
J 0
(-3350 4375);
DISPLAY 0.851064 (-3350 4375);
PAINT GREEN (-3350 4375);
DISPLAY INVISIBLE (-3350 4375);
FORCEADD VCC_CORE..1
(-4625 6000);
FORCEPROP 3 LASTPIN (-4625 5950) SIG_NAME PVDD18_S5_P1\g
J 0
(-4615 5960);
DISPLAY 0.659574 (-4615 5960);
PAINT MONO (-4615 5960);
DISPLAY INVISIBLE (-4615 5960);
FORCEPROP 1 LAST HDL_POWER PVDD18_S5_P1
J 1
(-4625 6050);
DISPLAY 0.489362 (-4625 6050);
PAINT GREEN (-4625 6050);
FORCEPROP 2 LAST CDS_LIB pure_quanta_power
J 0
(-4625 6000);
DISPLAY INVISIBLE (-4625 6000);
FORCEPROP 1 LAST PATH I737
J 0
(-4575 6025);
DISPLAY 0.872340 (-4575 6025);
PAINT AQUA (-4575 6025);
DISPLAY INVISIBLE (-4575 6025);
FORCEADD VCC_CORE..1
(-4625 5525);
FORCEPROP 3 LASTPIN (-4625 5475) SIG_NAME PVDD18_S5_P0\g
J 0
(-4615 5485);
DISPLAY 0.659574 (-4615 5485);
PAINT MONO (-4615 5485);
DISPLAY INVISIBLE (-4615 5485);
FORCEPROP 1 LAST HDL_POWER PVDD18_S5_P0
J 1
(-4625 5575);
DISPLAY 0.489362 (-4625 5575);
PAINT GREEN (-4625 5575);
FORCEPROP 2 LAST CDS_LIB pure_quanta_power
J 0
(-4625 5525);
DISPLAY INVISIBLE (-4625 5525);
FORCEPROP 1 LAST PATH I738
J 0
(-4575 5550);
DISPLAY 0.872340 (-4575 5550);
PAINT AQUA (-4575 5550);
DISPLAY INVISIBLE (-4575 5550);
FORCEADD VCC_CORE..1
(-4600 5025);
FORCEPROP 3 LASTPIN (-4600 4975) SIG_NAME P3V3\g
J 0
(-4590 4985);
DISPLAY 0.659574 (-4590 4985);
PAINT MONO (-4590 4985);
DISPLAY INVISIBLE (-4590 4985);
FORCEPROP 1 LAST HDL_POWER P3V3
J 1
(-4600 5075);
DISPLAY 0.489362 (-4600 5075);
PAINT GREEN (-4600 5075);
FORCEPROP 2 LAST CDS_LIB pure_quanta_power
J 0
(-4600 5025);
DISPLAY INVISIBLE (-4600 5025);
FORCEPROP 1 LAST PATH I739
J 0
(-4550 5050);
DISPLAY 0.872340 (-4550 5050);
PAINT AQUA (-4550 5050);
DISPLAY INVISIBLE (-4550 5050);
FORCEADD Q_RES..1
(-4900 5875);
FORCEPROP 1 LAST LOCATION R1285
J 0
(-5250 5875);
DISPLAY 0.489362 (-5250 5875);
PAINT SKYBLUE (-5250 5875);
FORCEPROP 0 LAST $SEC 1
J 0
(-5025 5925);
DISPLAY 0.680851 (-5025 5925);
PAINT MONO (-5025 5925);
DISPLAY INVISIBLE (-5025 5925);
FORCEPROP 0 LAST CDS_SEC 1
J 0
(-5025 5925);
DISPLAY 0.680851 (-5025 5925);
DISPLAY INVISIBLE (-5025 5925);
FORCEPROP 1 LASTPIN (-5000 5875) $PN 1
J 0
(-4988 5887);
DISPLAY 0.489362 (-4988 5887);
PAINT MONO (-4988 5887);
FORCEPROP 1 LASTPIN (-4800 5875) $PN 2
J 0
(-4838 5887);
DISPLAY 0.489362 (-4838 5887);
PAINT MONO (-4838 5887);
FORCEPROP 1 LAST VALUE 4.7K
J 0
(-4775 5875);
DISPLAY 0.489362 (-4775 5875);
PAINT SKYBLUE (-4775 5875);
FORCEPROP 2 LAST CDS_LIB pure_quanta
J 0
(-4900 5875);
DISPLAY INVISIBLE (-4900 5875);
FORCEPROP 1 LAST PATH I740
J 0
(-4950 6025);
DISPLAY 0.978723 (-4950 6025);
PAINT WHITE (-4950 6025);
DISPLAY INVISIBLE (-4950 6025);
FORCEPROP 1 LAST WATTAGE 1/16W
J 2
(-4925 5725);
DISPLAY 0.510638 (-4925 5725);
PAINT SKYBLUE (-4925 5725);
DISPLAY INVISIBLE (-4925 5725);
FORCEPROP 1 LAST MATERIAL CHIP
J 0
(-4800 5850);
DISPLAY 0.489362 (-4800 5850);
PAINT SKYBLUE (-4800 5850);
DISPLAY INVISIBLE (-4800 5850);
FORCEPROP 1 LAST TOLERANCE 5%
J 0
(-4775 5875);
DISPLAY 0.510638 (-4775 5875);
PAINT SKYBLUE (-4775 5875);
DISPLAY INVISIBLE (-4775 5875);
FORCEPROP 1 LAST PART_NUMBER TMP_QCS24702JB38
J 0
(-4950 5975);
DISPLAY 0.510638 (-4950 5975);
PAINT SKYBLUE (-4950 5975);
DISPLAY INVISIBLE (-4950 5975);
FORCEPROP 1 LAST PACK_TYPE 0402LF
J 0
(-4650 5725);
DISPLAY 0.510638 (-4650 5725);
PAINT SKYBLUE (-4650 5725);
DISPLAY INVISIBLE (-4650 5725);
FORCEADD Q_RES..1
(-4900 5825);
FORCEPROP 1 LAST LOCATION R1286
J 0
(-5250 5825);
DISPLAY 0.489362 (-5250 5825);
PAINT SKYBLUE (-5250 5825);
FORCEPROP 0 LAST $SEC 1
J 0
(-5025 5875);
DISPLAY 0.680851 (-5025 5875);
PAINT MONO (-5025 5875);
DISPLAY INVISIBLE (-5025 5875);
FORCEPROP 0 LAST CDS_SEC 1
J 0
(-5025 5875);
DISPLAY 0.680851 (-5025 5875);
DISPLAY INVISIBLE (-5025 5875);
FORCEPROP 1 LASTPIN (-5000 5825) $PN 1
J 0
(-4988 5837);
DISPLAY 0.489362 (-4988 5837);
PAINT MONO (-4988 5837);
FORCEPROP 1 LASTPIN (-4800 5825) $PN 2
J 0
(-4838 5837);
DISPLAY 0.489362 (-4838 5837);
PAINT MONO (-4838 5837);
FORCEPROP 1 LAST VALUE 4.7K
J 0
(-4775 5825);
DISPLAY 0.489362 (-4775 5825);
PAINT SKYBLUE (-4775 5825);
FORCEPROP 2 LAST CDS_LIB pure_quanta
J 0
(-4900 5825);
DISPLAY INVISIBLE (-4900 5825);
FORCEPROP 1 LAST PATH I741
J 0
(-4950 5975);
DISPLAY 0.978723 (-4950 5975);
PAINT WHITE (-4950 5975);
DISPLAY INVISIBLE (-4950 5975);
FORCEPROP 1 LAST WATTAGE 1/16W
J 2
(-4925 5675);
DISPLAY 0.510638 (-4925 5675);
PAINT SKYBLUE (-4925 5675);
DISPLAY INVISIBLE (-4925 5675);
FORCEPROP 1 LAST MATERIAL CHIP
J 0
(-4800 5800);
DISPLAY 0.489362 (-4800 5800);
PAINT SKYBLUE (-4800 5800);
DISPLAY INVISIBLE (-4800 5800);
FORCEPROP 1 LAST TOLERANCE 5%
J 0
(-4775 5825);
DISPLAY 0.510638 (-4775 5825);
PAINT SKYBLUE (-4775 5825);
DISPLAY INVISIBLE (-4775 5825);
FORCEPROP 1 LAST PART_NUMBER TMP_QCS24702JB38
J 0
(-4950 5925);
DISPLAY 0.510638 (-4950 5925);
PAINT SKYBLUE (-4950 5925);
DISPLAY INVISIBLE (-4950 5925);
FORCEPROP 1 LAST PACK_TYPE 0402LF
J 0
(-4650 5675);
DISPLAY 0.510638 (-4650 5675);
PAINT SKYBLUE (-4650 5675);
DISPLAY INVISIBLE (-4650 5675);
FORCEADD Q_RES..1
(-4900 5375);
FORCEPROP 1 LAST LOCATION R1287
J 0
(-5250 5375);
DISPLAY 0.489362 (-5250 5375);
PAINT SKYBLUE (-5250 5375);
FORCEPROP 0 LAST $SEC 1
J 0
(-5025 5425);
DISPLAY 0.680851 (-5025 5425);
PAINT MONO (-5025 5425);
DISPLAY INVISIBLE (-5025 5425);
FORCEPROP 0 LAST CDS_SEC 1
J 0
(-5025 5425);
DISPLAY 0.680851 (-5025 5425);
DISPLAY INVISIBLE (-5025 5425);
FORCEPROP 1 LASTPIN (-5000 5375) $PN 1
J 0
(-4988 5387);
DISPLAY 0.489362 (-4988 5387);
PAINT MONO (-4988 5387);
FORCEPROP 1 LASTPIN (-4800 5375) $PN 2
J 0
(-4838 5387);
DISPLAY 0.489362 (-4838 5387);
PAINT MONO (-4838 5387);
FORCEPROP 1 LAST VALUE 4.7K
J 0
(-4775 5375);
DISPLAY 0.489362 (-4775 5375);
PAINT SKYBLUE (-4775 5375);
FORCEPROP 2 LAST CDS_LIB pure_quanta
J 0
(-4900 5375);
DISPLAY INVISIBLE (-4900 5375);
FORCEPROP 1 LAST PATH I742
J 0
(-4950 5525);
DISPLAY 0.978723 (-4950 5525);
PAINT WHITE (-4950 5525);
DISPLAY INVISIBLE (-4950 5525);
FORCEPROP 1 LAST WATTAGE 1/16W
J 2
(-4925 5225);
DISPLAY 0.510638 (-4925 5225);
PAINT SKYBLUE (-4925 5225);
DISPLAY INVISIBLE (-4925 5225);
FORCEPROP 1 LAST MATERIAL CHIP
J 0
(-4800 5350);
DISPLAY 0.489362 (-4800 5350);
PAINT SKYBLUE (-4800 5350);
DISPLAY INVISIBLE (-4800 5350);
FORCEPROP 1 LAST TOLERANCE 5%
J 0
(-4775 5375);
DISPLAY 0.510638 (-4775 5375);
PAINT SKYBLUE (-4775 5375);
DISPLAY INVISIBLE (-4775 5375);
FORCEPROP 1 LAST PART_NUMBER TMP_QCS24702JB38
J 0
(-4950 5475);
DISPLAY 0.510638 (-4950 5475);
PAINT SKYBLUE (-4950 5475);
DISPLAY INVISIBLE (-4950 5475);
FORCEPROP 1 LAST PACK_TYPE 0402LF
J 0
(-4650 5225);
DISPLAY 0.510638 (-4650 5225);
PAINT SKYBLUE (-4650 5225);
DISPLAY INVISIBLE (-4650 5225);
FORCEADD Q_RES..1
(-4900 5325);
FORCEPROP 1 LAST LOCATION R1288
J 0
(-5250 5325);
DISPLAY 0.489362 (-5250 5325);
PAINT SKYBLUE (-5250 5325);
FORCEPROP 0 LAST $SEC 1
J 0
(-5025 5375);
DISPLAY 0.680851 (-5025 5375);
PAINT MONO (-5025 5375);
DISPLAY INVISIBLE (-5025 5375);
FORCEPROP 0 LAST CDS_SEC 1
J 0
(-5025 5375);
DISPLAY 0.680851 (-5025 5375);
DISPLAY INVISIBLE (-5025 5375);
FORCEPROP 1 LASTPIN (-5000 5325) $PN 1
J 0
(-4988 5337);
DISPLAY 0.489362 (-4988 5337);
PAINT MONO (-4988 5337);
FORCEPROP 1 LASTPIN (-4800 5325) $PN 2
J 0
(-4838 5337);
DISPLAY 0.489362 (-4838 5337);
PAINT MONO (-4838 5337);
FORCEPROP 1 LAST VALUE 4.7K
J 0
(-4775 5325);
DISPLAY 0.489362 (-4775 5325);
PAINT SKYBLUE (-4775 5325);
FORCEPROP 2 LAST CDS_LIB pure_quanta
J 0
(-4900 5325);
DISPLAY INVISIBLE (-4900 5325);
FORCEPROP 1 LAST PATH I743
J 0
(-4950 5475);
DISPLAY 0.978723 (-4950 5475);
PAINT WHITE (-4950 5475);
DISPLAY INVISIBLE (-4950 5475);
FORCEPROP 1 LAST WATTAGE 1/16W
J 2
(-4925 5175);
DISPLAY 0.510638 (-4925 5175);
PAINT SKYBLUE (-4925 5175);
DISPLAY INVISIBLE (-4925 5175);
FORCEPROP 1 LAST MATERIAL CHIP
J 0
(-4800 5300);
DISPLAY 0.489362 (-4800 5300);
PAINT SKYBLUE (-4800 5300);
DISPLAY INVISIBLE (-4800 5300);
FORCEPROP 1 LAST TOLERANCE 5%
J 0
(-4775 5325);
DISPLAY 0.510638 (-4775 5325);
PAINT SKYBLUE (-4775 5325);
DISPLAY INVISIBLE (-4775 5325);
FORCEPROP 1 LAST PART_NUMBER TMP_QCS24702JB38
J 0
(-4950 5425);
DISPLAY 0.510638 (-4950 5425);
PAINT SKYBLUE (-4950 5425);
DISPLAY INVISIBLE (-4950 5425);
FORCEPROP 1 LAST PACK_TYPE 0402LF
J 0
(-4650 5175);
DISPLAY 0.510638 (-4650 5175);
PAINT SKYBLUE (-4650 5175);
DISPLAY INVISIBLE (-4650 5175);
FORCEADD Q_RES..1
(-4900 5250);
FORCEPROP 1 LAST LOCATION R1351
J 0
(-5250 5250);
DISPLAY 0.489362 (-5250 5250);
PAINT SKYBLUE (-5250 5250);
FORCEPROP 0 LAST $SEC 1
J 0
(-4650 5300);
DISPLAY 0.680851 (-4650 5300);
PAINT MONO (-4650 5300);
DISPLAY INVISIBLE (-4650 5300);
FORCEPROP 0 LAST CDS_SEC 1
J 0
(-4700 5325);
DISPLAY 0.680851 (-4700 5325);
DISPLAY INVISIBLE (-4700 5325);
FORCEPROP 1 LASTPIN (-5000 5250) $PN 1
J 0
(-4988 5262);
DISPLAY 0.489362 (-4988 5262);
PAINT MONO (-4988 5262);
FORCEPROP 1 LASTPIN (-4800 5250) $PN 2
J 0
(-4838 5262);
DISPLAY 0.489362 (-4838 5262);
PAINT MONO (-4838 5262);
FORCEPROP 1 LAST VALUE 2.2K
J 2
(-4650 5250);
DISPLAY 0.489362 (-4650 5250);
PAINT SKYBLUE (-4650 5250);
FORCEPROP 2 LAST CDS_LIB pure_quanta
J 0
(-4900 5250);
DISPLAY INVISIBLE (-4900 5250);
FORCEPROP 1 LAST PATH I744
J 0
(-4950 5400);
DISPLAY 0.978723 (-4950 5400);
PAINT WHITE (-4950 5400);
DISPLAY INVISIBLE (-4950 5400);
FORCEPROP 1 LAST WATTAGE 1/16W
J 2
(-4925 5100);
DISPLAY 0.978723 (-4925 5100);
PAINT SKYBLUE (-4925 5100);
DISPLAY INVISIBLE (-4925 5100);
FORCEPROP 1 LAST MATERIAL CHIP
J 0
(-4900 5100);
DISPLAY 0.978723 (-4900 5100);
PAINT SKYBLUE (-4900 5100);
DISPLAY INVISIBLE (-4900 5100);
FORCEPROP 1 LAST TOLERANCE 5%
J 0
(-4900 5150);
DISPLAY 0.978723 (-4900 5150);
PAINT SKYBLUE (-4900 5150);
DISPLAY INVISIBLE (-4900 5150);
FORCEPROP 1 LAST PART_NUMBER CS22202JB07
J 0
(-4950 5350);
DISPLAY 0.978723 (-4950 5350);
PAINT SKYBLUE (-4950 5350);
DISPLAY INVISIBLE (-4950 5350);
FORCEPROP 1 LAST PACK_TYPE 0402LF
J 0
(-4650 5100);
DISPLAY 0.978723 (-4650 5100);
PAINT SKYBLUE (-4650 5100);
DISPLAY INVISIBLE (-4650 5100);
FORCEADD Q_RES..1
(-4900 4475);
FORCEPROP 1 LAST LOCATION R1191
J 0
(-5250 4475);
DISPLAY 0.489362 (-5250 4475);
PAINT SKYBLUE (-5250 4475);
FORCEPROP 2 LAST $SEC 1
J 0
(-4950 4675);
DISPLAY 0.680851 (-4950 4675);
PAINT MONO (-4950 4675);
DISPLAY INVISIBLE (-4950 4675);
FORCEPROP 2 LAST CDS_SEC 1
J 0
(-4950 4675);
DISPLAY 0.680851 (-4950 4675);
DISPLAY INVISIBLE (-4950 4675);
FORCEPROP 1 LASTPIN (-5000 4475) $PN 1
J 0
(-4988 4487);
DISPLAY 0.489362 (-4988 4487);
PAINT MONO (-4988 4487);
FORCEPROP 1 LASTPIN (-4800 4475) $PN 2
J 0
(-4838 4487);
DISPLAY 0.489362 (-4838 4487);
PAINT MONO (-4838 4487);
FORCEPROP 1 LAST VALUE 4.7K
J 0
(-4775 4475);
DISPLAY 0.489362 (-4775 4475);
PAINT SKYBLUE (-4775 4475);
FORCEPROP 2 LAST CDS_LIB pure_quanta
J 0
(-4900 4475);
DISPLAY INVISIBLE (-4900 4475);
FORCEPROP 1 LAST PATH I745
J 0
(-4950 4625);
DISPLAY 0.978723 (-4950 4625);
PAINT WHITE (-4950 4625);
DISPLAY INVISIBLE (-4950 4625);
FORCEPROP 1 LAST WATTAGE 1/16W
J 2
(-4925 4325);
DISPLAY 0.510638 (-4925 4325);
PAINT SKYBLUE (-4925 4325);
DISPLAY INVISIBLE (-4925 4325);
FORCEPROP 1 LAST MATERIAL CHIP
J 0
(-4800 4450);
DISPLAY 0.489362 (-4800 4450);
PAINT SKYBLUE (-4800 4450);
DISPLAY INVISIBLE (-4800 4450);
FORCEPROP 1 LAST TOLERANCE 5%
J 0
(-4775 4475);
DISPLAY 0.510638 (-4775 4475);
PAINT SKYBLUE (-4775 4475);
DISPLAY INVISIBLE (-4775 4475);
FORCEPROP 1 LAST PART_NUMBER TMP_QCS24702JB38
J 0
(-4950 4575);
DISPLAY 0.510638 (-4950 4575);
PAINT SKYBLUE (-4950 4575);
DISPLAY INVISIBLE (-4950 4575);
FORCEPROP 1 LAST PACK_TYPE 0402LF
J 0
(-4650 4325);
DISPLAY 0.510638 (-4650 4325);
PAINT SKYBLUE (-4650 4325);
DISPLAY INVISIBLE (-4650 4325);
FORCEADD Q_RES..1
(-4900 4425);
FORCEPROP 1 LAST LOCATION R1192
J 0
(-5250 4425);
DISPLAY 0.489362 (-5250 4425);
PAINT SKYBLUE (-5250 4425);
FORCEPROP 2 LAST $SEC 1
J 0
(-4950 4625);
DISPLAY 0.680851 (-4950 4625);
PAINT MONO (-4950 4625);
DISPLAY INVISIBLE (-4950 4625);
FORCEPROP 2 LAST CDS_SEC 1
J 0
(-4950 4625);
DISPLAY 0.680851 (-4950 4625);
DISPLAY INVISIBLE (-4950 4625);
FORCEPROP 1 LASTPIN (-5000 4425) $PN 1
J 0
(-4988 4437);
DISPLAY 0.489362 (-4988 4437);
PAINT MONO (-4988 4437);
FORCEPROP 1 LASTPIN (-4800 4425) $PN 2
J 0
(-4838 4437);
DISPLAY 0.489362 (-4838 4437);
PAINT MONO (-4838 4437);
FORCEPROP 1 LAST VALUE 4.7K
J 0
(-4775 4425);
DISPLAY 0.489362 (-4775 4425);
PAINT SKYBLUE (-4775 4425);
FORCEPROP 2 LAST CDS_LIB pure_quanta
J 0
(-4900 4425);
DISPLAY INVISIBLE (-4900 4425);
FORCEPROP 1 LAST PATH I746
J 0
(-4950 4575);
DISPLAY 0.978723 (-4950 4575);
PAINT WHITE (-4950 4575);
DISPLAY INVISIBLE (-4950 4575);
FORCEPROP 1 LAST WATTAGE 1/16W
J 2
(-4925 4275);
DISPLAY 0.510638 (-4925 4275);
PAINT SKYBLUE (-4925 4275);
DISPLAY INVISIBLE (-4925 4275);
FORCEPROP 1 LAST MATERIAL CHIP
J 0
(-4800 4400);
DISPLAY 0.489362 (-4800 4400);
PAINT SKYBLUE (-4800 4400);
DISPLAY INVISIBLE (-4800 4400);
FORCEPROP 1 LAST TOLERANCE 5%
J 0
(-4775 4425);
DISPLAY 0.510638 (-4775 4425);
PAINT SKYBLUE (-4775 4425);
DISPLAY INVISIBLE (-4775 4425);
FORCEPROP 1 LAST PART_NUMBER TMP_QCS24702JB38
J 0
(-4950 4525);
DISPLAY 0.510638 (-4950 4525);
PAINT SKYBLUE (-4950 4525);
DISPLAY INVISIBLE (-4950 4525);
FORCEPROP 1 LAST PACK_TYPE 0402LF
J 0
(-4650 4275);
DISPLAY 0.510638 (-4650 4275);
PAINT SKYBLUE (-4650 4275);
DISPLAY INVISIBLE (-4650 4275);
FORCEADD OFFPAGE..5
(-6100 5825);
FORCEPROP 2 LAST $XR1 54 
J 0
(-6414 5825);
DISPLAY 0.638298 (-6414 5825);
PAINT MONO (-6414 5825);
FORCEPROP 2 LAST $XR0 80 
J 0
(-6324 5825);
DISPLAY 0.638298 (-6324 5825);
PAINT MONO (-6324 5825);
FORCEPROP 2 LAST PATH I747
J 0
(-6300 5875);
DISPLAY 0.680851 (-6300 5875);
DISPLAY INVISIBLE (-6300 5875);
FORCEPROP 1 LAST COMMENT_BODY TRUE
J 0
(-6000 5750);
DISPLAY 0.872340 (-6000 5750);
PAINT GREEN (-6000 5750);
DISPLAY INVISIBLE (-6000 5750);
FORCEPROP 1 LAST OFFPAGE TRUE
J 0
(-5775 5700);
DISPLAY 0.872340 (-5775 5700);
PAINT GREEN (-5775 5700);
DISPLAY INVISIBLE (-5775 5700);
FORCEPROP 2 LAST CDS_LIB standard
J 0
(-6100 5825);
DISPLAY INVISIBLE (-6100 5825);
FORCEADD OFFPAGE..5
(-6100 5875);
FORCEPROP 2 LAST $XR1 54 
J 0
(-6414 5875);
DISPLAY 0.638298 (-6414 5875);
PAINT MONO (-6414 5875);
FORCEPROP 2 LAST $XR0 80 
J 0
(-6324 5875);
DISPLAY 0.638298 (-6324 5875);
PAINT MONO (-6324 5875);
FORCEPROP 2 LAST PATH I748
J 0
(-6300 5925);
DISPLAY 0.680851 (-6300 5925);
DISPLAY INVISIBLE (-6300 5925);
FORCEPROP 1 LAST COMMENT_BODY TRUE
J 0
(-6000 5800);
DISPLAY 0.872340 (-6000 5800);
PAINT GREEN (-6000 5800);
DISPLAY INVISIBLE (-6000 5800);
FORCEPROP 1 LAST OFFPAGE TRUE
J 0
(-5775 5750);
DISPLAY 0.872340 (-5775 5750);
PAINT GREEN (-5775 5750);
DISPLAY INVISIBLE (-5775 5750);
FORCEPROP 2 LAST CDS_LIB standard
J 0
(-6100 5875);
DISPLAY INVISIBLE (-6100 5875);
FORCEADD VCC_CORE..1
(-6800 6350);
FORCEPROP 3 LASTPIN (-6800 6300) SIG_NAME P1V8_STBY\g
J 0
(-6790 6310);
DISPLAY 0.659574 (-6790 6310);
PAINT MONO (-6790 6310);
DISPLAY INVISIBLE (-6790 6310);
FORCEPROP 1 LAST HDL_POWER P1V8_STBY
J 1
(-6800 6400);
DISPLAY 0.489362 (-6800 6400);
PAINT GREEN (-6800 6400);
FORCEPROP 2 LAST CDS_LIB pure_quanta_power
J 0
(-6800 6350);
DISPLAY INVISIBLE (-6800 6350);
FORCEPROP 1 LAST PATH I749
J 0
(-6750 6375);
DISPLAY 0.872340 (-6750 6375);
PAINT AQUA (-6750 6375);
DISPLAY INVISIBLE (-6750 6375);
FORCEADD VCC_CORE..1
(-6775 5625);
FORCEPROP 3 LASTPIN (-6775 5575) SIG_NAME P3V3_STBY\g
J 0
(-6765 5585);
DISPLAY 0.659574 (-6765 5585);
PAINT MONO (-6765 5585);
DISPLAY INVISIBLE (-6765 5585);
FORCEPROP 1 LAST HDL_POWER P3V3_STBY
J 1
(-6775 5675);
DISPLAY 0.489362 (-6775 5675);
PAINT GREEN (-6775 5675);
FORCEPROP 1 LAST PATH I750
J 0
(-6725 5650);
DISPLAY 0.872340 (-6725 5650);
PAINT AQUA (-6725 5650);
DISPLAY INVISIBLE (-6725 5650);
FORCEPROP 2 LAST CDS_LIB pure_quanta_power
J 0
(-6775 5625);
DISPLAY INVISIBLE (-6775 5625);
FORCEADD OFFPAGE..5
(-6075 5375);
FORCEPROP 2 LAST $XR1 27 
J 0
(-6389 5375);
DISPLAY 0.638298 (-6389 5375);
PAINT MONO (-6389 5375);
FORCEPROP 2 LAST $XR0 80 
J 0
(-6299 5375);
DISPLAY 0.638298 (-6299 5375);
PAINT MONO (-6299 5375);
FORCEPROP 2 LAST PATH I751
J 0
(-6325 5425);
DISPLAY 0.680851 (-6325 5425);
DISPLAY INVISIBLE (-6325 5425);
FORCEPROP 1 LAST COMMENT_BODY TRUE
J 0
(-5975 5300);
DISPLAY 0.872340 (-5975 5300);
PAINT GREEN (-5975 5300);
DISPLAY INVISIBLE (-5975 5300);
FORCEPROP 1 LAST OFFPAGE TRUE
J 0
(-5750 5250);
DISPLAY 0.872340 (-5750 5250);
PAINT GREEN (-5750 5250);
DISPLAY INVISIBLE (-5750 5250);
FORCEPROP 2 LAST CDS_LIB standard
J 0
(-6075 5375);
DISPLAY INVISIBLE (-6075 5375);
FORCEADD OFFPAGE..5
(-6075 5325);
FORCEPROP 2 LAST $XR1 27 
J 0
(-6389 5325);
DISPLAY 0.638298 (-6389 5325);
PAINT MONO (-6389 5325);
FORCEPROP 2 LAST $XR0 80 
J 0
(-6299 5325);
DISPLAY 0.638298 (-6299 5325);
PAINT MONO (-6299 5325);
FORCEPROP 2 LAST PATH I752
J 0
(-6325 5375);
DISPLAY 0.680851 (-6325 5375);
DISPLAY INVISIBLE (-6325 5375);
FORCEPROP 1 LAST COMMENT_BODY TRUE
J 0
(-5975 5250);
DISPLAY 0.872340 (-5975 5250);
PAINT GREEN (-5975 5250);
DISPLAY INVISIBLE (-5975 5250);
FORCEPROP 1 LAST OFFPAGE TRUE
J 0
(-5750 5200);
DISPLAY 0.872340 (-5750 5200);
PAINT GREEN (-5750 5200);
DISPLAY INVISIBLE (-5750 5200);
FORCEPROP 2 LAST CDS_LIB standard
J 0
(-6075 5325);
DISPLAY INVISIBLE (-6075 5325);
FORCEADD OFFPAGE..5
(-6075 5250);
FORCEPROP 2 LAST $XR1 29 
J 0
(-6389 5250);
DISPLAY 0.638298 (-6389 5250);
PAINT MONO (-6389 5250);
FORCEPROP 2 LAST $XR0 80 
J 0
(-6299 5250);
DISPLAY 0.638298 (-6299 5250);
PAINT MONO (-6299 5250);
FORCEPROP 2 LAST PATH I753
J 0
(-6325 5300);
DISPLAY 0.680851 (-6325 5300);
DISPLAY INVISIBLE (-6325 5300);
FORCEPROP 1 LAST COMMENT_BODY TRUE
J 0
(-5975 5175);
DISPLAY 0.872340 (-5975 5175);
PAINT GREEN (-5975 5175);
DISPLAY INVISIBLE (-5975 5175);
FORCEPROP 1 LAST OFFPAGE TRUE
J 0
(-5750 5125);
DISPLAY 0.872340 (-5750 5125);
PAINT GREEN (-5750 5125);
DISPLAY INVISIBLE (-5750 5125);
FORCEPROP 2 LAST CDS_LIB standard
J 0
(-6075 5250);
DISPLAY INVISIBLE (-6075 5250);
FORCEADD OFFPAGE..5
(-6050 4475);
FORCEPROP 2 LAST $XR1 81 
J 0
(-6425 4475);
DISPLAY 0.638298 (-6425 4475);
PAINT MONO (-6425 4475);
FORCEPROP 2 LAST $XR0 128 
J 0
(-6335 4475);
DISPLAY 0.638298 (-6335 4475);
PAINT MONO (-6335 4475);
FORCEPROP 2 LAST PATH I754
J 0
(-6325 4525);
DISPLAY 0.680851 (-6325 4525);
DISPLAY INVISIBLE (-6325 4525);
FORCEPROP 1 LAST COMMENT_BODY TRUE
J 0
(-5950 4400);
DISPLAY 0.872340 (-5950 4400);
PAINT GREEN (-5950 4400);
DISPLAY INVISIBLE (-5950 4400);
FORCEPROP 1 LAST OFFPAGE TRUE
J 0
(-5725 4350);
DISPLAY 0.872340 (-5725 4350);
PAINT GREEN (-5725 4350);
DISPLAY INVISIBLE (-5725 4350);
FORCEPROP 2 LAST CDS_LIB standard
J 0
(-6050 4475);
DISPLAY INVISIBLE (-6050 4475);
FORCEADD OFFPAGE..5
(-6050 4425);
FORCEPROP 2 LAST $XR1 81 
J 0
(-6425 4425);
DISPLAY 0.638298 (-6425 4425);
PAINT MONO (-6425 4425);
FORCEPROP 2 LAST $XR0 128 
J 0
(-6335 4425);
DISPLAY 0.638298 (-6335 4425);
PAINT MONO (-6335 4425);
FORCEPROP 2 LAST PATH I755
J 0
(-6325 4475);
DISPLAY 0.680851 (-6325 4475);
DISPLAY INVISIBLE (-6325 4475);
FORCEPROP 1 LAST COMMENT_BODY TRUE
J 0
(-5950 4350);
DISPLAY 0.872340 (-5950 4350);
PAINT GREEN (-5950 4350);
DISPLAY INVISIBLE (-5950 4350);
FORCEPROP 1 LAST OFFPAGE TRUE
J 0
(-5725 4300);
DISPLAY 0.872340 (-5725 4300);
PAINT GREEN (-5725 4300);
DISPLAY INVISIBLE (-5725 4300);
FORCEPROP 2 LAST CDS_LIB standard
J 0
(-6050 4425);
DISPLAY INVISIBLE (-6050 4425);
FORCEADD Q_RES..1
(-7025 5825);
FORCEPROP 1 LAST LOCATION R960
J 0
(-7250 5825);
DISPLAY 0.489362 (-7250 5825);
PAINT SKYBLUE (-7250 5825);
FORCEPROP 0 LAST $SEC 1
J 0
(-7075 5925);
DISPLAY 0.680851 (-7075 5925);
PAINT MONO (-7075 5925);
DISPLAY INVISIBLE (-7075 5925);
FORCEPROP 0 LAST CDS_SEC 1
J 0
(-7075 5925);
DISPLAY 0.680851 (-7075 5925);
DISPLAY INVISIBLE (-7075 5925);
FORCEPROP 1 LASTPIN (-7125 5825) $PN 1
J 0
(-7113 5837);
DISPLAY 0.489362 (-7113 5837);
PAINT MONO (-7113 5837);
FORCEPROP 1 LASTPIN (-6925 5825) $PN 2
J 0
(-6963 5837);
DISPLAY 0.489362 (-6963 5837);
PAINT MONO (-6963 5837);
FORCEPROP 1 LAST VALUE 4.7K
J 0
(-6900 5825);
DISPLAY 0.489362 (-6900 5825);
PAINT SKYBLUE (-6900 5825);
FORCEPROP 2 LAST CDS_LIB pure_quanta
J 0
(-7025 5825);
DISPLAY INVISIBLE (-7025 5825);
FORCEPROP 1 LAST PATH I756
J 0
(-7075 5975);
DISPLAY 0.978723 (-7075 5975);
PAINT WHITE (-7075 5975);
DISPLAY INVISIBLE (-7075 5975);
FORCEPROP 1 LAST WATTAGE 1/16W
J 2
(-7050 5675);
DISPLAY 0.510638 (-7050 5675);
PAINT SKYBLUE (-7050 5675);
DISPLAY INVISIBLE (-7050 5675);
FORCEPROP 1 LAST MATERIAL CHIP
J 0
(-6925 5800);
DISPLAY 0.489362 (-6925 5800);
PAINT SKYBLUE (-6925 5800);
DISPLAY INVISIBLE (-6925 5800);
FORCEPROP 1 LAST TOLERANCE 5%
J 0
(-6900 5825);
DISPLAY 0.510638 (-6900 5825);
PAINT SKYBLUE (-6900 5825);
DISPLAY INVISIBLE (-6900 5825);
FORCEPROP 1 LAST PART_NUMBER TMP_QCS24702JB38
J 0
(-7075 5925);
DISPLAY 0.510638 (-7075 5925);
PAINT SKYBLUE (-7075 5925);
DISPLAY INVISIBLE (-7075 5925);
FORCEPROP 1 LAST PACK_TYPE 0402LF
J 0
(-6775 5675);
DISPLAY 0.510638 (-6775 5675);
PAINT SKYBLUE (-6775 5675);
DISPLAY INVISIBLE (-6775 5675);
FORCEADD Q_RES..1
(-7025 5775);
FORCEPROP 1 LAST LOCATION R961
J 0
(-7250 5775);
DISPLAY 0.489362 (-7250 5775);
PAINT SKYBLUE (-7250 5775);
FORCEPROP 0 LAST $SEC 1
J 0
(-7075 5875);
DISPLAY 0.680851 (-7075 5875);
PAINT MONO (-7075 5875);
DISPLAY INVISIBLE (-7075 5875);
FORCEPROP 0 LAST CDS_SEC 1
J 0
(-7075 5875);
DISPLAY 0.680851 (-7075 5875);
DISPLAY INVISIBLE (-7075 5875);
FORCEPROP 1 LASTPIN (-7125 5775) $PN 1
J 0
(-7113 5787);
DISPLAY 0.489362 (-7113 5787);
PAINT MONO (-7113 5787);
FORCEPROP 1 LASTPIN (-6925 5775) $PN 2
J 0
(-6963 5787);
DISPLAY 0.489362 (-6963 5787);
PAINT MONO (-6963 5787);
FORCEPROP 1 LAST VALUE 4.7K
J 0
(-6900 5775);
DISPLAY 0.489362 (-6900 5775);
PAINT SKYBLUE (-6900 5775);
FORCEPROP 2 LAST CDS_LIB pure_quanta
J 0
(-7025 5775);
DISPLAY INVISIBLE (-7025 5775);
FORCEPROP 1 LAST PATH I757
J 0
(-7075 5925);
DISPLAY 0.978723 (-7075 5925);
PAINT WHITE (-7075 5925);
DISPLAY INVISIBLE (-7075 5925);
FORCEPROP 1 LAST WATTAGE 1/16W
J 2
(-7050 5625);
DISPLAY 0.510638 (-7050 5625);
PAINT SKYBLUE (-7050 5625);
DISPLAY INVISIBLE (-7050 5625);
FORCEPROP 1 LAST MATERIAL CHIP
J 0
(-6925 5750);
DISPLAY 0.489362 (-6925 5750);
PAINT SKYBLUE (-6925 5750);
DISPLAY INVISIBLE (-6925 5750);
FORCEPROP 1 LAST TOLERANCE 5%
J 0
(-6900 5775);
DISPLAY 0.510638 (-6900 5775);
PAINT SKYBLUE (-6900 5775);
DISPLAY INVISIBLE (-6900 5775);
FORCEPROP 1 LAST PART_NUMBER TMP_QCS24702JB38
J 0
(-7075 5875);
DISPLAY 0.510638 (-7075 5875);
PAINT SKYBLUE (-7075 5875);
DISPLAY INVISIBLE (-7075 5875);
FORCEPROP 1 LAST PACK_TYPE 0402LF
J 0
(-6775 5625);
DISPLAY 0.510638 (-6775 5625);
PAINT SKYBLUE (-6775 5625);
DISPLAY INVISIBLE (-6775 5625);
FORCEADD Q_RES..1
(-7025 5725);
FORCEPROP 1 LAST LOCATION R654
J 0
(-7250 5725);
DISPLAY 0.489362 (-7250 5725);
PAINT SKYBLUE (-7250 5725);
FORCEPROP 2 LAST $SEC 1
J 0
(-7075 5925);
DISPLAY 0.680851 (-7075 5925);
PAINT MONO (-7075 5925);
DISPLAY INVISIBLE (-7075 5925);
FORCEPROP 2 LAST CDS_SEC 1
J 0
(-7075 5925);
DISPLAY 0.680851 (-7075 5925);
DISPLAY INVISIBLE (-7075 5925);
FORCEPROP 1 LASTPIN (-7125 5725) $PN 1
J 0
(-7113 5737);
DISPLAY 0.489362 (-7113 5737);
PAINT MONO (-7113 5737);
FORCEPROP 1 LASTPIN (-6925 5725) $PN 2
J 0
(-6963 5737);
DISPLAY 0.489362 (-6963 5737);
PAINT MONO (-6963 5737);
FORCEPROP 1 LAST VALUE 4.7K
J 0
(-6900 5725);
DISPLAY 0.489362 (-6900 5725);
PAINT SKYBLUE (-6900 5725);
FORCEPROP 2 LAST CDS_LIB pure_quanta
J 0
(-7025 5725);
DISPLAY INVISIBLE (-7025 5725);
FORCEPROP 1 LAST PATH I758
J 0
(-7075 5875);
DISPLAY 0.978723 (-7075 5875);
PAINT WHITE (-7075 5875);
DISPLAY INVISIBLE (-7075 5875);
FORCEPROP 1 LAST WATTAGE 1/16W
J 2
(-7050 5575);
DISPLAY 0.510638 (-7050 5575);
PAINT SKYBLUE (-7050 5575);
DISPLAY INVISIBLE (-7050 5575);
FORCEPROP 1 LAST MATERIAL CHIP
J 0
(-6925 5700);
DISPLAY 0.489362 (-6925 5700);
PAINT SKYBLUE (-6925 5700);
DISPLAY INVISIBLE (-6925 5700);
FORCEPROP 1 LAST TOLERANCE 5%
J 0
(-6900 5725);
DISPLAY 0.510638 (-6900 5725);
PAINT SKYBLUE (-6900 5725);
DISPLAY INVISIBLE (-6900 5725);
FORCEPROP 1 LAST PART_NUMBER TMP_QCS24702JB38
J 0
(-7075 5825);
DISPLAY 0.510638 (-7075 5825);
PAINT SKYBLUE (-7075 5825);
DISPLAY INVISIBLE (-7075 5825);
FORCEPROP 1 LAST PACK_TYPE 0402LF
J 0
(-6775 5575);
DISPLAY 0.510638 (-6775 5575);
PAINT SKYBLUE (-6775 5575);
DISPLAY INVISIBLE (-6775 5575);
FORCEADD Q_RES..1
(-7025 5550);
FORCEPROP 1 LAST LOCATION R1185
J 0
(-7325 5550);
DISPLAY 0.489362 (-7325 5550);
PAINT SKYBLUE (-7325 5550);
FORCEPROP 0 LAST $SEC 1
J 0
(-7325 5600);
DISPLAY 0.680851 (-7325 5600);
PAINT MONO (-7325 5600);
DISPLAY INVISIBLE (-7325 5600);
FORCEPROP 0 LAST CDS_SEC 1
J 0
(-7325 5600);
DISPLAY 0.680851 (-7325 5600);
DISPLAY INVISIBLE (-7325 5600);
FORCEPROP 1 LASTPIN (-7125 5550) $PN 1
J 0
(-7113 5562);
DISPLAY 0.489362 (-7113 5562);
PAINT MONO (-7113 5562);
FORCEPROP 1 LASTPIN (-6925 5550) $PN 2
J 0
(-6963 5562);
DISPLAY 0.489362 (-6963 5562);
PAINT MONO (-6963 5562);
FORCEPROP 1 LAST VALUE 4.7K
J 0
(-6900 5550);
DISPLAY 0.489362 (-6900 5550);
PAINT SKYBLUE (-6900 5550);
FORCEPROP 2 LAST CDS_LIB pure_quanta
J 0
(-7025 5550);
DISPLAY INVISIBLE (-7025 5550);
FORCEPROP 1 LAST PATH I759
J 0
(-7075 5700);
DISPLAY 0.978723 (-7075 5700);
PAINT WHITE (-7075 5700);
DISPLAY INVISIBLE (-7075 5700);
FORCEPROP 1 LAST WATTAGE 1/16W
J 2
(-7050 5400);
DISPLAY 0.510638 (-7050 5400);
PAINT SKYBLUE (-7050 5400);
DISPLAY INVISIBLE (-7050 5400);
FORCEPROP 1 LAST MATERIAL CHIP
J 0
(-6925 5525);
DISPLAY 0.489362 (-6925 5525);
PAINT SKYBLUE (-6925 5525);
DISPLAY INVISIBLE (-6925 5525);
FORCEPROP 1 LAST TOLERANCE 5%
J 0
(-6900 5550);
DISPLAY 0.510638 (-6900 5550);
PAINT SKYBLUE (-6900 5550);
DISPLAY INVISIBLE (-6900 5550);
FORCEPROP 1 LAST PART_NUMBER TMP_QCS24702JB38
J 0
(-7075 5650);
DISPLAY 0.510638 (-7075 5650);
PAINT SKYBLUE (-7075 5650);
DISPLAY INVISIBLE (-7075 5650);
FORCEPROP 1 LAST PACK_TYPE 0402LF
J 0
(-6775 5400);
DISPLAY 0.510638 (-6775 5400);
PAINT SKYBLUE (-6775 5400);
DISPLAY INVISIBLE (-6775 5400);
FORCEADD Q_RES..1
(-7025 5350);
FORCEPROP 1 LAST LOCATION R1189
J 0
(-7325 5350);
DISPLAY 0.489362 (-7325 5350);
PAINT SKYBLUE (-7325 5350);
FORCEPROP 0 LAST $SEC 1
J 0
(-7325 5400);
DISPLAY 0.680851 (-7325 5400);
PAINT MONO (-7325 5400);
DISPLAY INVISIBLE (-7325 5400);
FORCEPROP 0 LAST CDS_SEC 1
J 0
(-7325 5400);
DISPLAY 0.680851 (-7325 5400);
DISPLAY INVISIBLE (-7325 5400);
FORCEPROP 1 LASTPIN (-7125 5350) $PN 1
J 0
(-7113 5362);
DISPLAY 0.489362 (-7113 5362);
PAINT MONO (-7113 5362);
FORCEPROP 1 LASTPIN (-6925 5350) $PN 2
J 0
(-6963 5362);
DISPLAY 0.489362 (-6963 5362);
PAINT MONO (-6963 5362);
FORCEPROP 1 LAST VALUE 4.7K
J 0
(-6900 5350);
DISPLAY 0.489362 (-6900 5350);
PAINT SKYBLUE (-6900 5350);
FORCEPROP 2 LAST CDS_LIB pure_quanta
J 0
(-7025 5350);
DISPLAY INVISIBLE (-7025 5350);
FORCEPROP 1 LAST PATH I760
J 0
(-7075 5500);
DISPLAY 0.978723 (-7075 5500);
PAINT WHITE (-7075 5500);
DISPLAY INVISIBLE (-7075 5500);
FORCEPROP 1 LAST WATTAGE 1/16W
J 2
(-7050 5200);
DISPLAY 0.510638 (-7050 5200);
PAINT SKYBLUE (-7050 5200);
DISPLAY INVISIBLE (-7050 5200);
FORCEPROP 1 LAST MATERIAL CHIP
J 0
(-6925 5325);
DISPLAY 0.489362 (-6925 5325);
PAINT SKYBLUE (-6925 5325);
DISPLAY INVISIBLE (-6925 5325);
FORCEPROP 1 LAST TOLERANCE 5%
J 0
(-6900 5350);
DISPLAY 0.510638 (-6900 5350);
PAINT SKYBLUE (-6900 5350);
DISPLAY INVISIBLE (-6900 5350);
FORCEPROP 1 LAST PART_NUMBER TMP_QCS24702JB38
J 0
(-7075 5450);
DISPLAY 0.510638 (-7075 5450);
PAINT SKYBLUE (-7075 5450);
DISPLAY INVISIBLE (-7075 5450);
FORCEPROP 1 LAST PACK_TYPE 0402LF
J 0
(-6775 5200);
DISPLAY 0.510638 (-6775 5200);
PAINT SKYBLUE (-6775 5200);
DISPLAY INVISIBLE (-6775 5200);
FORCEADD Q_RES..1
(-7025 5400);
FORCEPROP 1 LAST LOCATION R1188
J 0
(-7325 5400);
DISPLAY 0.489362 (-7325 5400);
PAINT SKYBLUE (-7325 5400);
FORCEPROP 0 LAST $SEC 1
J 0
(-7325 5450);
DISPLAY 0.680851 (-7325 5450);
PAINT MONO (-7325 5450);
DISPLAY INVISIBLE (-7325 5450);
FORCEPROP 0 LAST CDS_SEC 1
J 0
(-7325 5450);
DISPLAY 0.680851 (-7325 5450);
DISPLAY INVISIBLE (-7325 5450);
FORCEPROP 1 LASTPIN (-7125 5400) $PN 1
J 0
(-7113 5412);
DISPLAY 0.489362 (-7113 5412);
PAINT MONO (-7113 5412);
FORCEPROP 1 LASTPIN (-6925 5400) $PN 2
J 0
(-6963 5412);
DISPLAY 0.489362 (-6963 5412);
PAINT MONO (-6963 5412);
FORCEPROP 1 LAST VALUE 4.7K
J 0
(-6900 5400);
DISPLAY 0.489362 (-6900 5400);
PAINT SKYBLUE (-6900 5400);
FORCEPROP 2 LAST CDS_LIB pure_quanta
J 0
(-7025 5400);
DISPLAY INVISIBLE (-7025 5400);
FORCEPROP 1 LAST PATH I761
J 0
(-7075 5550);
DISPLAY 0.978723 (-7075 5550);
PAINT WHITE (-7075 5550);
DISPLAY INVISIBLE (-7075 5550);
FORCEPROP 1 LAST WATTAGE 1/16W
J 2
(-7050 5250);
DISPLAY 0.510638 (-7050 5250);
PAINT SKYBLUE (-7050 5250);
DISPLAY INVISIBLE (-7050 5250);
FORCEPROP 1 LAST MATERIAL CHIP
J 0
(-6925 5375);
DISPLAY 0.489362 (-6925 5375);
PAINT SKYBLUE (-6925 5375);
DISPLAY INVISIBLE (-6925 5375);
FORCEPROP 1 LAST TOLERANCE 5%
J 0
(-6900 5400);
DISPLAY 0.510638 (-6900 5400);
PAINT SKYBLUE (-6900 5400);
DISPLAY INVISIBLE (-6900 5400);
FORCEPROP 1 LAST PART_NUMBER TMP_QCS24702JB38
J 0
(-7075 5500);
DISPLAY 0.510638 (-7075 5500);
PAINT SKYBLUE (-7075 5500);
DISPLAY INVISIBLE (-7075 5500);
FORCEPROP 1 LAST PACK_TYPE 0402LF
J 0
(-6775 5250);
DISPLAY 0.510638 (-6775 5250);
PAINT SKYBLUE (-6775 5250);
DISPLAY INVISIBLE (-6775 5250);
FORCEADD Q_RES..1
(-7025 5500);
FORCEPROP 1 LAST LOCATION R1186
J 0
(-7325 5500);
DISPLAY 0.489362 (-7325 5500);
PAINT SKYBLUE (-7325 5500);
FORCEPROP 0 LAST $SEC 1
J 0
(-7325 5550);
DISPLAY 0.680851 (-7325 5550);
PAINT MONO (-7325 5550);
DISPLAY INVISIBLE (-7325 5550);
FORCEPROP 0 LAST CDS_SEC 1
J 0
(-7325 5550);
DISPLAY 0.680851 (-7325 5550);
DISPLAY INVISIBLE (-7325 5550);
FORCEPROP 1 LASTPIN (-7125 5500) $PN 1
J 0
(-7113 5512);
DISPLAY 0.489362 (-7113 5512);
PAINT MONO (-7113 5512);
FORCEPROP 1 LASTPIN (-6925 5500) $PN 2
J 0
(-6963 5512);
DISPLAY 0.489362 (-6963 5512);
PAINT MONO (-6963 5512);
FORCEPROP 1 LAST VALUE 4.7K
J 0
(-6900 5500);
DISPLAY 0.489362 (-6900 5500);
PAINT SKYBLUE (-6900 5500);
FORCEPROP 2 LAST CDS_LIB pure_quanta
J 0
(-7025 5500);
DISPLAY INVISIBLE (-7025 5500);
FORCEPROP 1 LAST PATH I762
J 0
(-7075 5650);
DISPLAY 0.978723 (-7075 5650);
PAINT WHITE (-7075 5650);
DISPLAY INVISIBLE (-7075 5650);
FORCEPROP 1 LAST WATTAGE 1/16W
J 2
(-7050 5350);
DISPLAY 0.510638 (-7050 5350);
PAINT SKYBLUE (-7050 5350);
DISPLAY INVISIBLE (-7050 5350);
FORCEPROP 1 LAST MATERIAL CHIP
J 0
(-6925 5475);
DISPLAY 0.489362 (-6925 5475);
PAINT SKYBLUE (-6925 5475);
DISPLAY INVISIBLE (-6925 5475);
FORCEPROP 1 LAST TOLERANCE 5%
J 0
(-6900 5500);
DISPLAY 0.510638 (-6900 5500);
PAINT SKYBLUE (-6900 5500);
DISPLAY INVISIBLE (-6900 5500);
FORCEPROP 1 LAST PART_NUMBER TMP_QCS24702JB38
J 0
(-7075 5600);
DISPLAY 0.510638 (-7075 5600);
PAINT SKYBLUE (-7075 5600);
DISPLAY INVISIBLE (-7075 5600);
FORCEPROP 1 LAST PACK_TYPE 0402LF
J 0
(-6775 5350);
DISPLAY 0.510638 (-6775 5350);
PAINT SKYBLUE (-6775 5350);
DISPLAY INVISIBLE (-6775 5350);
FORCEADD Q_RES..1
(-7025 5300);
FORCEPROP 1 LAST LOCATION R1190
J 0
(-7325 5300);
DISPLAY 0.489362 (-7325 5300);
PAINT SKYBLUE (-7325 5300);
FORCEPROP 0 LAST $SEC 1
J 0
(-7325 5350);
DISPLAY 0.680851 (-7325 5350);
PAINT MONO (-7325 5350);
DISPLAY INVISIBLE (-7325 5350);
FORCEPROP 0 LAST CDS_SEC 1
J 0
(-7325 5350);
DISPLAY 0.680851 (-7325 5350);
DISPLAY INVISIBLE (-7325 5350);
FORCEPROP 1 LASTPIN (-7125 5300) $PN 1
J 0
(-7113 5312);
DISPLAY 0.489362 (-7113 5312);
PAINT MONO (-7113 5312);
FORCEPROP 1 LASTPIN (-6925 5300) $PN 2
J 0
(-6963 5312);
DISPLAY 0.489362 (-6963 5312);
PAINT MONO (-6963 5312);
FORCEPROP 1 LAST VALUE 4.7K
J 0
(-6900 5300);
DISPLAY 0.489362 (-6900 5300);
PAINT SKYBLUE (-6900 5300);
FORCEPROP 2 LAST CDS_LIB pure_quanta
J 0
(-7025 5300);
DISPLAY INVISIBLE (-7025 5300);
FORCEPROP 1 LAST PATH I763
J 0
(-7075 5450);
DISPLAY 0.978723 (-7075 5450);
PAINT WHITE (-7075 5450);
DISPLAY INVISIBLE (-7075 5450);
FORCEPROP 1 LAST WATTAGE 1/16W
J 2
(-7050 5150);
DISPLAY 0.510638 (-7050 5150);
PAINT SKYBLUE (-7050 5150);
DISPLAY INVISIBLE (-7050 5150);
FORCEPROP 1 LAST MATERIAL CHIP
J 0
(-6925 5275);
DISPLAY 0.489362 (-6925 5275);
PAINT SKYBLUE (-6925 5275);
DISPLAY INVISIBLE (-6925 5275);
FORCEPROP 1 LAST TOLERANCE 5%
J 0
(-6900 5300);
DISPLAY 0.510638 (-6900 5300);
PAINT SKYBLUE (-6900 5300);
DISPLAY INVISIBLE (-6900 5300);
FORCEPROP 1 LAST PART_NUMBER TMP_QCS24702JB38
J 0
(-7075 5400);
DISPLAY 0.510638 (-7075 5400);
PAINT SKYBLUE (-7075 5400);
DISPLAY INVISIBLE (-7075 5400);
FORCEPROP 1 LAST PACK_TYPE 0402LF
J 0
(-6775 5150);
DISPLAY 0.510638 (-6775 5150);
PAINT SKYBLUE (-6775 5150);
DISPLAY INVISIBLE (-6775 5150);
FORCEADD Q_RES..1
(-7025 5450);
FORCEPROP 1 LAST LOCATION R1187
J 0
(-7325 5450);
DISPLAY 0.489362 (-7325 5450);
PAINT SKYBLUE (-7325 5450);
FORCEPROP 0 LAST $SEC 1
J 0
(-7325 5500);
DISPLAY 0.680851 (-7325 5500);
PAINT MONO (-7325 5500);
DISPLAY INVISIBLE (-7325 5500);
FORCEPROP 0 LAST CDS_SEC 1
J 0
(-7325 5500);
DISPLAY 0.680851 (-7325 5500);
DISPLAY INVISIBLE (-7325 5500);
FORCEPROP 1 LASTPIN (-7125 5450) $PN 1
J 0
(-7113 5462);
DISPLAY 0.489362 (-7113 5462);
PAINT MONO (-7113 5462);
FORCEPROP 1 LASTPIN (-6925 5450) $PN 2
J 0
(-6963 5462);
DISPLAY 0.489362 (-6963 5462);
PAINT MONO (-6963 5462);
FORCEPROP 1 LAST VALUE 4.7K
J 0
(-6900 5450);
DISPLAY 0.489362 (-6900 5450);
PAINT SKYBLUE (-6900 5450);
FORCEPROP 2 LAST CDS_LIB pure_quanta
J 0
(-7025 5450);
DISPLAY INVISIBLE (-7025 5450);
FORCEPROP 1 LAST PATH I764
J 0
(-7075 5600);
DISPLAY 0.978723 (-7075 5600);
PAINT WHITE (-7075 5600);
DISPLAY INVISIBLE (-7075 5600);
FORCEPROP 1 LAST WATTAGE 1/16W
J 2
(-7050 5300);
DISPLAY 0.510638 (-7050 5300);
PAINT SKYBLUE (-7050 5300);
DISPLAY INVISIBLE (-7050 5300);
FORCEPROP 1 LAST MATERIAL CHIP
J 0
(-6925 5425);
DISPLAY 0.489362 (-6925 5425);
PAINT SKYBLUE (-6925 5425);
DISPLAY INVISIBLE (-6925 5425);
FORCEPROP 1 LAST TOLERANCE 5%
J 0
(-6900 5450);
DISPLAY 0.510638 (-6900 5450);
PAINT SKYBLUE (-6900 5450);
DISPLAY INVISIBLE (-6900 5450);
FORCEPROP 1 LAST PART_NUMBER TMP_QCS24702JB38
J 0
(-7075 5550);
DISPLAY 0.510638 (-7075 5550);
PAINT SKYBLUE (-7075 5550);
DISPLAY INVISIBLE (-7075 5550);
FORCEPROP 1 LAST PACK_TYPE 0402LF
J 0
(-6775 5300);
DISPLAY 0.510638 (-6775 5300);
PAINT SKYBLUE (-6775 5300);
DISPLAY INVISIBLE (-6775 5300);
FORCEADD Q_RES..1
(-7025 5100);
FORCEPROP 1 LAST LOCATION R668
J 0
(-7325 5100);
DISPLAY 0.489362 (-7325 5100);
PAINT SKYBLUE (-7325 5100);
FORCEPROP 2 LAST $SEC 1
J 0
(-7075 5300);
DISPLAY 0.680851 (-7075 5300);
PAINT MONO (-7075 5300);
DISPLAY INVISIBLE (-7075 5300);
FORCEPROP 2 LAST CDS_SEC 1
J 0
(-7075 5300);
DISPLAY 1.021277 (-7075 5300);
DISPLAY INVISIBLE (-7075 5300);
FORCEPROP 1 LASTPIN (-7125 5100) $PN 1
J 0
(-7110 5110);
DISPLAY 0.489362 (-7110 5110);
PAINT MONO (-7110 5110);
FORCEPROP 1 LASTPIN (-6925 5100) $PN 2
J 0
(-6963 5112);
DISPLAY 0.489362 (-6963 5112);
PAINT MONO (-6963 5112);
FORCEPROP 1 LAST VALUE 4.7K
J 0
(-6900 5100);
DISPLAY 0.489362 (-6900 5100);
PAINT SKYBLUE (-6900 5100);
FORCEPROP 2 LAST CDS_LIB pure_quanta
J 0
(-7025 5100);
DISPLAY INVISIBLE (-7025 5100);
FORCEPROP 1 LAST PATH I765
J 0
(-7075 5250);
DISPLAY 0.978723 (-7075 5250);
PAINT WHITE (-7075 5250);
DISPLAY INVISIBLE (-7075 5250);
FORCEPROP 1 LAST WATTAGE 1/16W
J 2
(-7050 4950);
DISPLAY 0.510638 (-7050 4950);
PAINT SKYBLUE (-7050 4950);
DISPLAY INVISIBLE (-7050 4950);
FORCEPROP 1 LAST MATERIAL CHIP
J 0
(-6925 5075);
DISPLAY 0.489362 (-6925 5075);
PAINT SKYBLUE (-6925 5075);
DISPLAY INVISIBLE (-6925 5075);
FORCEPROP 1 LAST TOLERANCE 5%
J 0
(-6900 5100);
DISPLAY 0.510638 (-6900 5100);
PAINT SKYBLUE (-6900 5100);
DISPLAY INVISIBLE (-6900 5100);
FORCEPROP 1 LAST PART_NUMBER TMP_QCS24702JB38
J 0
(-7075 5200);
DISPLAY 0.510638 (-7075 5200);
PAINT SKYBLUE (-7075 5200);
DISPLAY INVISIBLE (-7075 5200);
FORCEPROP 1 LAST PACK_TYPE 0402LF
J 0
(-6775 4950);
DISPLAY 0.510638 (-6775 4950);
PAINT SKYBLUE (-6775 4950);
DISPLAY INVISIBLE (-6775 4950);
FORCEADD Q_RES..1
(-7025 4675);
FORCEPROP 1 LAST LOCATION R1181
J 0
(-7325 4675);
DISPLAY 0.489362 (-7325 4675);
PAINT SKYBLUE (-7325 4675);
FORCEPROP 2 LAST $SEC 1
J 0
(-7075 4875);
DISPLAY 0.680851 (-7075 4875);
PAINT MONO (-7075 4875);
DISPLAY INVISIBLE (-7075 4875);
FORCEPROP 2 LAST CDS_SEC 1
J 0
(-7075 4875);
DISPLAY 0.680851 (-7075 4875);
DISPLAY INVISIBLE (-7075 4875);
FORCEPROP 1 LASTPIN (-7125 4675) $PN 1
J 0
(-7113 4687);
DISPLAY 0.489362 (-7113 4687);
PAINT MONO (-7113 4687);
FORCEPROP 1 LASTPIN (-6925 4675) $PN 2
J 0
(-6963 4687);
DISPLAY 0.489362 (-6963 4687);
PAINT MONO (-6963 4687);
FORCEPROP 1 LAST VALUE 4.7K
J 0
(-6900 4675);
DISPLAY 0.489362 (-6900 4675);
PAINT SKYBLUE (-6900 4675);
FORCEPROP 2 LAST CDS_LIB pure_quanta
J 0
(-7025 4675);
DISPLAY INVISIBLE (-7025 4675);
FORCEPROP 1 LAST PATH I768
J 0
(-7075 4825);
DISPLAY 0.978723 (-7075 4825);
PAINT WHITE (-7075 4825);
DISPLAY INVISIBLE (-7075 4825);
FORCEPROP 1 LAST WATTAGE 1/16W
J 2
(-7050 4525);
DISPLAY 0.510638 (-7050 4525);
PAINT SKYBLUE (-7050 4525);
DISPLAY INVISIBLE (-7050 4525);
FORCEPROP 1 LAST MATERIAL CHIP
J 0
(-6925 4650);
DISPLAY 0.489362 (-6925 4650);
PAINT SKYBLUE (-6925 4650);
DISPLAY INVISIBLE (-6925 4650);
FORCEPROP 1 LAST TOLERANCE 5%
J 0
(-6900 4675);
DISPLAY 0.510638 (-6900 4675);
PAINT SKYBLUE (-6900 4675);
DISPLAY INVISIBLE (-6900 4675);
FORCEPROP 1 LAST PART_NUMBER TMP_QCS24702JB38
J 0
(-7075 4775);
DISPLAY 0.510638 (-7075 4775);
PAINT SKYBLUE (-7075 4775);
DISPLAY INVISIBLE (-7075 4775);
FORCEPROP 1 LAST PACK_TYPE 0402LF
J 0
(-6775 4525);
DISPLAY 0.510638 (-6775 4525);
PAINT SKYBLUE (-6775 4525);
DISPLAY INVISIBLE (-6775 4525);
FORCEADD Q_RES..1
(-7025 4725);
FORCEPROP 1 LAST LOCATION R1180
J 0
(-7325 4725);
DISPLAY 0.489362 (-7325 4725);
PAINT SKYBLUE (-7325 4725);
FORCEPROP 2 LAST $SEC 1
J 0
(-7075 4925);
DISPLAY 0.680851 (-7075 4925);
PAINT MONO (-7075 4925);
DISPLAY INVISIBLE (-7075 4925);
FORCEPROP 2 LAST CDS_SEC 1
J 0
(-7075 4925);
DISPLAY 0.680851 (-7075 4925);
DISPLAY INVISIBLE (-7075 4925);
FORCEPROP 1 LASTPIN (-7125 4725) $PN 1
J 0
(-7113 4737);
DISPLAY 0.489362 (-7113 4737);
PAINT MONO (-7113 4737);
FORCEPROP 1 LASTPIN (-6925 4725) $PN 2
J 0
(-6963 4737);
DISPLAY 0.489362 (-6963 4737);
PAINT MONO (-6963 4737);
FORCEPROP 1 LAST VALUE 4.7K
J 0
(-6900 4725);
DISPLAY 0.489362 (-6900 4725);
PAINT SKYBLUE (-6900 4725);
FORCEPROP 2 LAST CDS_LIB pure_quanta
J 0
(-7025 4725);
DISPLAY INVISIBLE (-7025 4725);
FORCEPROP 1 LAST PATH I769
J 0
(-7075 4875);
DISPLAY 0.978723 (-7075 4875);
PAINT WHITE (-7075 4875);
DISPLAY INVISIBLE (-7075 4875);
FORCEPROP 1 LAST WATTAGE 1/16W
J 2
(-7050 4575);
DISPLAY 0.510638 (-7050 4575);
PAINT SKYBLUE (-7050 4575);
DISPLAY INVISIBLE (-7050 4575);
FORCEPROP 1 LAST MATERIAL CHIP
J 0
(-6925 4700);
DISPLAY 0.489362 (-6925 4700);
PAINT SKYBLUE (-6925 4700);
DISPLAY INVISIBLE (-6925 4700);
FORCEPROP 1 LAST TOLERANCE 5%
J 0
(-6900 4725);
DISPLAY 0.510638 (-6900 4725);
PAINT SKYBLUE (-6900 4725);
DISPLAY INVISIBLE (-6900 4725);
FORCEPROP 1 LAST PART_NUMBER TMP_QCS24702JB38
J 0
(-7075 4825);
DISPLAY 0.510638 (-7075 4825);
PAINT SKYBLUE (-7075 4825);
DISPLAY INVISIBLE (-7075 4825);
FORCEPROP 1 LAST PACK_TYPE 0402LF
J 0
(-6775 4575);
DISPLAY 0.510638 (-6775 4575);
PAINT SKYBLUE (-6775 4575);
DISPLAY INVISIBLE (-6775 4575);
FORCEADD Q_RES..1
(-7025 4975);
FORCEPROP 1 LAST LOCATION R656
J 0
(-7325 4975);
DISPLAY 0.489362 (-7325 4975);
PAINT SKYBLUE (-7325 4975);
FORCEPROP 2 LAST $SEC 1
J 0
(-7075 5175);
DISPLAY 0.680851 (-7075 5175);
PAINT MONO (-7075 5175);
DISPLAY INVISIBLE (-7075 5175);
FORCEPROP 2 LAST CDS_SEC 1
J 0
(-7075 5175);
DISPLAY 0.680851 (-7075 5175);
DISPLAY INVISIBLE (-7075 5175);
FORCEPROP 1 LASTPIN (-7125 4975) $PN 1
J 0
(-7113 4987);
DISPLAY 0.489362 (-7113 4987);
PAINT MONO (-7113 4987);
FORCEPROP 1 LASTPIN (-6925 4975) $PN 2
J 0
(-6963 4987);
DISPLAY 0.489362 (-6963 4987);
PAINT MONO (-6963 4987);
FORCEPROP 1 LAST VALUE 4.7K
J 0
(-6900 4975);
DISPLAY 0.489362 (-6900 4975);
PAINT SKYBLUE (-6900 4975);
FORCEPROP 2 LAST CDS_LIB pure_quanta
J 0
(-7025 4975);
DISPLAY INVISIBLE (-7025 4975);
FORCEPROP 1 LAST PATH I770
J 0
(-7075 5125);
DISPLAY 0.978723 (-7075 5125);
PAINT WHITE (-7075 5125);
DISPLAY INVISIBLE (-7075 5125);
FORCEPROP 1 LAST WATTAGE 1/16W
J 2
(-7050 4825);
DISPLAY 0.510638 (-7050 4825);
PAINT SKYBLUE (-7050 4825);
DISPLAY INVISIBLE (-7050 4825);
FORCEPROP 1 LAST MATERIAL CHIP
J 0
(-6925 4950);
DISPLAY 0.489362 (-6925 4950);
PAINT SKYBLUE (-6925 4950);
DISPLAY INVISIBLE (-6925 4950);
FORCEPROP 1 LAST TOLERANCE 5%
J 0
(-6900 4975);
DISPLAY 0.510638 (-6900 4975);
PAINT SKYBLUE (-6900 4975);
DISPLAY INVISIBLE (-6900 4975);
FORCEPROP 1 LAST PART_NUMBER TMP_QCS24702JB38
J 0
(-7075 5075);
DISPLAY 0.510638 (-7075 5075);
PAINT SKYBLUE (-7075 5075);
DISPLAY INVISIBLE (-7075 5075);
FORCEPROP 1 LAST PACK_TYPE 0402LF
J 0
(-6775 4825);
DISPLAY 0.510638 (-6775 4825);
PAINT SKYBLUE (-6775 4825);
DISPLAY INVISIBLE (-6775 4825);
FORCEADD Q_RES..1
(-7025 5025);
FORCEPROP 1 LAST LOCATION R655
J 0
(-7325 5025);
DISPLAY 0.489362 (-7325 5025);
PAINT SKYBLUE (-7325 5025);
FORCEPROP 2 LAST $SEC 1
J 0
(-7075 5225);
DISPLAY 0.680851 (-7075 5225);
PAINT MONO (-7075 5225);
DISPLAY INVISIBLE (-7075 5225);
FORCEPROP 2 LAST CDS_SEC 1
J 0
(-7075 5225);
DISPLAY 0.680851 (-7075 5225);
DISPLAY INVISIBLE (-7075 5225);
FORCEPROP 1 LASTPIN (-7125 5025) $PN 1
J 0
(-7113 5037);
DISPLAY 0.489362 (-7113 5037);
PAINT MONO (-7113 5037);
FORCEPROP 1 LASTPIN (-6925 5025) $PN 2
J 0
(-6963 5037);
DISPLAY 0.489362 (-6963 5037);
PAINT MONO (-6963 5037);
FORCEPROP 1 LAST VALUE 4.7K
J 0
(-6900 5025);
DISPLAY 0.489362 (-6900 5025);
PAINT SKYBLUE (-6900 5025);
FORCEPROP 2 LAST CDS_LIB pure_quanta
J 0
(-7025 5025);
DISPLAY INVISIBLE (-7025 5025);
FORCEPROP 1 LAST PATH I771
J 0
(-7075 5175);
DISPLAY 0.978723 (-7075 5175);
PAINT WHITE (-7075 5175);
DISPLAY INVISIBLE (-7075 5175);
FORCEPROP 1 LAST WATTAGE 1/16W
J 2
(-7050 4875);
DISPLAY 0.510638 (-7050 4875);
PAINT SKYBLUE (-7050 4875);
DISPLAY INVISIBLE (-7050 4875);
FORCEPROP 1 LAST MATERIAL CHIP
J 0
(-6925 5000);
DISPLAY 0.489362 (-6925 5000);
PAINT SKYBLUE (-6925 5000);
DISPLAY INVISIBLE (-6925 5000);
FORCEPROP 1 LAST TOLERANCE 5%
J 0
(-6900 5025);
DISPLAY 0.510638 (-6900 5025);
PAINT SKYBLUE (-6900 5025);
DISPLAY INVISIBLE (-6900 5025);
FORCEPROP 1 LAST PART_NUMBER TMP_QCS24702JB38
J 0
(-7075 5125);
DISPLAY 0.510638 (-7075 5125);
PAINT SKYBLUE (-7075 5125);
DISPLAY INVISIBLE (-7075 5125);
FORCEPROP 1 LAST PACK_TYPE 0402LF
J 0
(-6775 4875);
DISPLAY 0.510638 (-6775 4875);
PAINT SKYBLUE (-6775 4875);
DISPLAY INVISIBLE (-6775 4875);
FORCEADD Q_RES..1
(-7025 4625);
FORCEPROP 1 LAST LOCATION R1182
J 0
(-7325 4625);
DISPLAY 0.489362 (-7325 4625);
PAINT SKYBLUE (-7325 4625);
FORCEPROP 2 LAST $SEC 1
J 0
(-7075 4825);
DISPLAY 0.680851 (-7075 4825);
PAINT MONO (-7075 4825);
DISPLAY INVISIBLE (-7075 4825);
FORCEPROP 2 LAST CDS_SEC 1
J 0
(-7075 4825);
DISPLAY 0.680851 (-7075 4825);
DISPLAY INVISIBLE (-7075 4825);
FORCEPROP 1 LASTPIN (-7125 4625) $PN 1
J 0
(-7113 4637);
DISPLAY 0.489362 (-7113 4637);
PAINT MONO (-7113 4637);
FORCEPROP 1 LASTPIN (-6925 4625) $PN 2
J 0
(-6963 4637);
DISPLAY 0.489362 (-6963 4637);
PAINT MONO (-6963 4637);
FORCEPROP 1 LAST VALUE 4.7K
J 0
(-6900 4625);
DISPLAY 0.489362 (-6900 4625);
PAINT SKYBLUE (-6900 4625);
FORCEPROP 2 LAST CDS_LIB pure_quanta
J 0
(-7025 4625);
DISPLAY INVISIBLE (-7025 4625);
FORCEPROP 1 LAST PATH I772
J 0
(-7075 4775);
DISPLAY 0.978723 (-7075 4775);
PAINT WHITE (-7075 4775);
DISPLAY INVISIBLE (-7075 4775);
FORCEPROP 1 LAST WATTAGE 1/16W
J 2
(-7050 4475);
DISPLAY 0.510638 (-7050 4475);
PAINT SKYBLUE (-7050 4475);
DISPLAY INVISIBLE (-7050 4475);
FORCEPROP 1 LAST MATERIAL CHIP
J 0
(-6925 4600);
DISPLAY 0.489362 (-6925 4600);
PAINT SKYBLUE (-6925 4600);
DISPLAY INVISIBLE (-6925 4600);
FORCEPROP 1 LAST TOLERANCE 5%
J 0
(-6900 4625);
DISPLAY 0.510638 (-6900 4625);
PAINT SKYBLUE (-6900 4625);
DISPLAY INVISIBLE (-6900 4625);
FORCEPROP 1 LAST PART_NUMBER TMP_QCS24702JB38
J 0
(-7075 4725);
DISPLAY 0.510638 (-7075 4725);
PAINT SKYBLUE (-7075 4725);
DISPLAY INVISIBLE (-7075 4725);
FORCEPROP 1 LAST PACK_TYPE 0402LF
J 0
(-6775 4475);
DISPLAY 0.510638 (-6775 4475);
PAINT SKYBLUE (-6775 4475);
DISPLAY INVISIBLE (-6775 4475);
FORCEADD Q_RES..1
(-7025 4400);
FORCEPROP 1 LAST LOCATION R1307
J 0
(-7325 4400);
DISPLAY 0.489362 (-7325 4400);
PAINT SKYBLUE (-7325 4400);
FORCEPROP 0 LAST $SEC 1
J 0
(-7325 4450);
DISPLAY 0.680851 (-7325 4450);
PAINT MONO (-7325 4450);
DISPLAY INVISIBLE (-7325 4450);
FORCEPROP 0 LAST CDS_SEC 1
J 0
(-7325 4450);
DISPLAY 0.680851 (-7325 4450);
DISPLAY INVISIBLE (-7325 4450);
FORCEPROP 1 LASTPIN (-7125 4400) $PN 1
J 0
(-7113 4412);
DISPLAY 0.489362 (-7113 4412);
PAINT MONO (-7113 4412);
FORCEPROP 1 LASTPIN (-6925 4400) $PN 2
J 0
(-6963 4412);
DISPLAY 0.489362 (-6963 4412);
PAINT MONO (-6963 4412);
FORCEPROP 1 LAST VALUE 4.7K
J 0
(-6900 4400);
DISPLAY 0.489362 (-6900 4400);
PAINT SKYBLUE (-6900 4400);
FORCEPROP 2 LAST CDS_LIB pure_quanta
J 0
(-7025 4400);
DISPLAY INVISIBLE (-7025 4400);
FORCEPROP 1 LAST PATH I773
J 0
(-7075 4550);
DISPLAY 0.978723 (-7075 4550);
PAINT WHITE (-7075 4550);
DISPLAY INVISIBLE (-7075 4550);
FORCEPROP 1 LAST WATTAGE 1/16W
J 2
(-7050 4250);
DISPLAY 0.510638 (-7050 4250);
PAINT SKYBLUE (-7050 4250);
DISPLAY INVISIBLE (-7050 4250);
FORCEPROP 1 LAST MATERIAL CHIP
J 0
(-6925 4375);
DISPLAY 0.489362 (-6925 4375);
PAINT SKYBLUE (-6925 4375);
DISPLAY INVISIBLE (-6925 4375);
FORCEPROP 1 LAST TOLERANCE 5%
J 0
(-6900 4400);
DISPLAY 0.510638 (-6900 4400);
PAINT SKYBLUE (-6900 4400);
DISPLAY INVISIBLE (-6900 4400);
FORCEPROP 1 LAST PART_NUMBER TMP_QCS24702JB38
J 0
(-7075 4500);
DISPLAY 0.510638 (-7075 4500);
PAINT SKYBLUE (-7075 4500);
DISPLAY INVISIBLE (-7075 4500);
FORCEPROP 1 LAST PACK_TYPE 0402LF
J 0
(-6775 4250);
DISPLAY 0.510638 (-6775 4250);
PAINT SKYBLUE (-6775 4250);
DISPLAY INVISIBLE (-6775 4250);
FORCEADD Q_RES..1
(-7025 4450);
FORCEPROP 1 LAST LOCATION R1306
J 0
(-7325 4450);
DISPLAY 0.489362 (-7325 4450);
PAINT SKYBLUE (-7325 4450);
FORCEPROP 0 LAST $SEC 1
J 0
(-7325 4500);
DISPLAY 0.680851 (-7325 4500);
PAINT MONO (-7325 4500);
DISPLAY INVISIBLE (-7325 4500);
FORCEPROP 0 LAST CDS_SEC 1
J 0
(-7325 4500);
DISPLAY 0.680851 (-7325 4500);
DISPLAY INVISIBLE (-7325 4500);
FORCEPROP 1 LASTPIN (-7125 4450) $PN 1
J 0
(-7113 4462);
DISPLAY 0.489362 (-7113 4462);
PAINT MONO (-7113 4462);
FORCEPROP 1 LASTPIN (-6925 4450) $PN 2
J 0
(-6963 4462);
DISPLAY 0.489362 (-6963 4462);
PAINT MONO (-6963 4462);
FORCEPROP 1 LAST VALUE 4.7K
J 0
(-6900 4450);
DISPLAY 0.489362 (-6900 4450);
PAINT SKYBLUE (-6900 4450);
FORCEPROP 2 LAST CDS_LIB pure_quanta
J 0
(-7025 4450);
DISPLAY INVISIBLE (-7025 4450);
FORCEPROP 1 LAST PATH I774
J 0
(-7075 4600);
DISPLAY 0.978723 (-7075 4600);
PAINT WHITE (-7075 4600);
DISPLAY INVISIBLE (-7075 4600);
FORCEPROP 1 LAST WATTAGE 1/16W
J 2
(-7050 4300);
DISPLAY 0.510638 (-7050 4300);
PAINT SKYBLUE (-7050 4300);
DISPLAY INVISIBLE (-7050 4300);
FORCEPROP 1 LAST MATERIAL CHIP
J 0
(-6925 4425);
DISPLAY 0.489362 (-6925 4425);
PAINT SKYBLUE (-6925 4425);
DISPLAY INVISIBLE (-6925 4425);
FORCEPROP 1 LAST TOLERANCE 5%
J 0
(-6900 4450);
DISPLAY 0.510638 (-6900 4450);
PAINT SKYBLUE (-6900 4450);
DISPLAY INVISIBLE (-6900 4450);
FORCEPROP 1 LAST PART_NUMBER TMP_QCS24702JB38
J 0
(-7075 4550);
DISPLAY 0.510638 (-7075 4550);
PAINT SKYBLUE (-7075 4550);
DISPLAY INVISIBLE (-7075 4550);
FORCEPROP 1 LAST PACK_TYPE 0402LF
J 0
(-6775 4300);
DISPLAY 0.510638 (-6775 4300);
PAINT SKYBLUE (-6775 4300);
DISPLAY INVISIBLE (-6775 4300);
FORCEADD Q_RES..1
(-7025 4500);
FORCEPROP 1 LAST LOCATION R1305
J 0
(-7325 4500);
DISPLAY 0.489362 (-7325 4500);
PAINT SKYBLUE (-7325 4500);
FORCEPROP 0 LAST $SEC 1
J 0
(-7325 4550);
DISPLAY 0.680851 (-7325 4550);
PAINT MONO (-7325 4550);
DISPLAY INVISIBLE (-7325 4550);
FORCEPROP 0 LAST CDS_SEC 1
J 0
(-7325 4550);
DISPLAY 0.680851 (-7325 4550);
DISPLAY INVISIBLE (-7325 4550);
FORCEPROP 1 LASTPIN (-7125 4500) $PN 1
J 0
(-7113 4512);
DISPLAY 0.489362 (-7113 4512);
PAINT MONO (-7113 4512);
FORCEPROP 1 LASTPIN (-6925 4500) $PN 2
J 0
(-6963 4512);
DISPLAY 0.489362 (-6963 4512);
PAINT MONO (-6963 4512);
FORCEPROP 1 LAST VALUE 4.7K
J 0
(-6900 4500);
DISPLAY 0.489362 (-6900 4500);
PAINT SKYBLUE (-6900 4500);
FORCEPROP 2 LAST CDS_LIB pure_quanta
J 0
(-7025 4500);
DISPLAY INVISIBLE (-7025 4500);
FORCEPROP 1 LAST PATH I775
J 0
(-7075 4650);
DISPLAY 0.978723 (-7075 4650);
PAINT WHITE (-7075 4650);
DISPLAY INVISIBLE (-7075 4650);
FORCEPROP 1 LAST WATTAGE 1/16W
J 2
(-7050 4350);
DISPLAY 0.510638 (-7050 4350);
PAINT SKYBLUE (-7050 4350);
DISPLAY INVISIBLE (-7050 4350);
FORCEPROP 1 LAST MATERIAL CHIP
J 0
(-6925 4475);
DISPLAY 0.489362 (-6925 4475);
PAINT SKYBLUE (-6925 4475);
DISPLAY INVISIBLE (-6925 4475);
FORCEPROP 1 LAST TOLERANCE 5%
J 0
(-6900 4500);
DISPLAY 0.510638 (-6900 4500);
PAINT SKYBLUE (-6900 4500);
DISPLAY INVISIBLE (-6900 4500);
FORCEPROP 1 LAST PART_NUMBER TMP_QCS24702JB38
J 0
(-7075 4600);
DISPLAY 0.510638 (-7075 4600);
PAINT SKYBLUE (-7075 4600);
DISPLAY INVISIBLE (-7075 4600);
FORCEPROP 1 LAST PACK_TYPE 0402LF
J 0
(-6775 4350);
DISPLAY 0.510638 (-6775 4350);
PAINT SKYBLUE (-6775 4350);
DISPLAY INVISIBLE (-6775 4350);
FORCEADD Q_RES..1
(-7025 4550);
FORCEPROP 1 LAST LOCATION R1304
J 0
(-7325 4550);
DISPLAY 0.489362 (-7325 4550);
PAINT SKYBLUE (-7325 4550);
FORCEPROP 0 LAST $SEC 1
J 0
(-7325 4600);
DISPLAY 0.680851 (-7325 4600);
PAINT MONO (-7325 4600);
DISPLAY INVISIBLE (-7325 4600);
FORCEPROP 0 LAST CDS_SEC 1
J 0
(-7325 4600);
DISPLAY 0.680851 (-7325 4600);
DISPLAY INVISIBLE (-7325 4600);
FORCEPROP 1 LASTPIN (-7125 4550) $PN 1
J 0
(-7113 4562);
DISPLAY 0.489362 (-7113 4562);
PAINT MONO (-7113 4562);
FORCEPROP 1 LASTPIN (-6925 4550) $PN 2
J 0
(-6963 4562);
DISPLAY 0.489362 (-6963 4562);
PAINT MONO (-6963 4562);
FORCEPROP 1 LAST VALUE 4.7K
J 0
(-6900 4550);
DISPLAY 0.489362 (-6900 4550);
PAINT SKYBLUE (-6900 4550);
FORCEPROP 2 LAST CDS_LIB pure_quanta
J 0
(-7025 4550);
DISPLAY INVISIBLE (-7025 4550);
FORCEPROP 1 LAST PATH I776
J 0
(-7075 4700);
DISPLAY 0.978723 (-7075 4700);
PAINT WHITE (-7075 4700);
DISPLAY INVISIBLE (-7075 4700);
FORCEPROP 1 LAST WATTAGE 1/16W
J 2
(-7050 4400);
DISPLAY 0.510638 (-7050 4400);
PAINT SKYBLUE (-7050 4400);
DISPLAY INVISIBLE (-7050 4400);
FORCEPROP 1 LAST MATERIAL CHIP
J 0
(-6925 4525);
DISPLAY 0.489362 (-6925 4525);
PAINT SKYBLUE (-6925 4525);
DISPLAY INVISIBLE (-6925 4525);
FORCEPROP 1 LAST TOLERANCE 5%
J 0
(-6900 4550);
DISPLAY 0.510638 (-6900 4550);
PAINT SKYBLUE (-6900 4550);
DISPLAY INVISIBLE (-6900 4550);
FORCEPROP 1 LAST PART_NUMBER TMP_QCS24702JB38
J 0
(-7075 4650);
DISPLAY 0.510638 (-7075 4650);
PAINT SKYBLUE (-7075 4650);
DISPLAY INVISIBLE (-7075 4650);
FORCEPROP 1 LAST PACK_TYPE 0402LF
J 0
(-6775 4400);
DISPLAY 0.510638 (-6775 4400);
PAINT SKYBLUE (-6775 4400);
DISPLAY INVISIBLE (-6775 4400);
FORCEADD Q_RES..1
(-7025 4175);
FORCEPROP 1 LAST LOCATION R1314
J 0
(-7325 4175);
DISPLAY 0.489362 (-7325 4175);
PAINT SKYBLUE (-7325 4175);
FORCEPROP 0 LAST $SEC 1
J 0
(-7325 4225);
DISPLAY 0.680851 (-7325 4225);
PAINT MONO (-7325 4225);
DISPLAY INVISIBLE (-7325 4225);
FORCEPROP 0 LAST CDS_SEC 1
J 0
(-7325 4225);
DISPLAY 0.680851 (-7325 4225);
DISPLAY INVISIBLE (-7325 4225);
FORCEPROP 1 LASTPIN (-7125 4175) $PN 1
J 0
(-7113 4187);
DISPLAY 0.489362 (-7113 4187);
PAINT MONO (-7113 4187);
FORCEPROP 1 LASTPIN (-6925 4175) $PN 2
J 0
(-6963 4187);
DISPLAY 0.489362 (-6963 4187);
PAINT MONO (-6963 4187);
FORCEPROP 1 LAST MATERIAL EMPTY
J 0
(-6925 4150);
DISPLAY 0.489362 (-6925 4150);
PAINT RED (-6925 4150);
FORCEPROP 1 LAST VALUE 4.7K
J 0
(-6900 4175);
DISPLAY 0.489362 (-6900 4175);
PAINT SKYBLUE (-6900 4175);
FORCEPROP 2 LAST CDS_LIB pure_quanta
J 0
(-7025 4175);
DISPLAY INVISIBLE (-7025 4175);
FORCEPROP 1 LAST PATH I777
J 0
(-7075 4325);
DISPLAY 0.978723 (-7075 4325);
PAINT WHITE (-7075 4325);
DISPLAY INVISIBLE (-7075 4325);
FORCEPROP 1 LAST WATTAGE 1/16W
J 2
(-7050 4025);
DISPLAY 0.510638 (-7050 4025);
PAINT SKYBLUE (-7050 4025);
DISPLAY INVISIBLE (-7050 4025);
FORCEPROP 1 LAST TOLERANCE 5%
J 0
(-6900 4175);
DISPLAY 0.510638 (-6900 4175);
PAINT SKYBLUE (-6900 4175);
DISPLAY INVISIBLE (-6900 4175);
FORCEPROP 1 LAST PART_NUMBER TMP_QCS24702JB38
J 0
(-7075 4275);
DISPLAY 0.510638 (-7075 4275);
PAINT SKYBLUE (-7075 4275);
DISPLAY INVISIBLE (-7075 4275);
FORCEPROP 1 LAST PACK_TYPE 0402LF
J 0
(-6775 4025);
DISPLAY 0.510638 (-6775 4025);
PAINT SKYBLUE (-6775 4025);
DISPLAY INVISIBLE (-6775 4025);
FORCEADD Q_RES..1
(-7025 4125);
FORCEPROP 1 LAST LOCATION R1315
J 0
(-7325 4125);
DISPLAY 0.489362 (-7325 4125);
PAINT SKYBLUE (-7325 4125);
FORCEPROP 0 LAST $SEC 1
J 0
(-7325 4175);
DISPLAY 0.680851 (-7325 4175);
PAINT MONO (-7325 4175);
DISPLAY INVISIBLE (-7325 4175);
FORCEPROP 0 LAST CDS_SEC 1
J 0
(-7325 4175);
DISPLAY 0.680851 (-7325 4175);
DISPLAY INVISIBLE (-7325 4175);
FORCEPROP 1 LASTPIN (-7125 4125) $PN 1
J 0
(-7113 4137);
DISPLAY 0.489362 (-7113 4137);
PAINT MONO (-7113 4137);
FORCEPROP 1 LASTPIN (-6925 4125) $PN 2
J 0
(-6963 4137);
DISPLAY 0.489362 (-6963 4137);
PAINT MONO (-6963 4137);
FORCEPROP 1 LAST VALUE 4.7K
J 0
(-6900 4125);
DISPLAY 0.489362 (-6900 4125);
PAINT SKYBLUE (-6900 4125);
FORCEPROP 1 LAST MATERIAL EMPTY
J 0
(-6925 4100);
DISPLAY 0.489362 (-6925 4100);
PAINT RED (-6925 4100);
FORCEPROP 2 LAST CDS_LIB pure_quanta
J 0
(-7025 4125);
DISPLAY INVISIBLE (-7025 4125);
FORCEPROP 1 LAST PATH I778
J 0
(-7075 4275);
DISPLAY 0.978723 (-7075 4275);
PAINT WHITE (-7075 4275);
DISPLAY INVISIBLE (-7075 4275);
FORCEPROP 1 LAST WATTAGE 1/16W
J 2
(-7050 3975);
DISPLAY 0.510638 (-7050 3975);
PAINT SKYBLUE (-7050 3975);
DISPLAY INVISIBLE (-7050 3975);
FORCEPROP 1 LAST TOLERANCE 5%
J 0
(-6900 4125);
DISPLAY 0.510638 (-6900 4125);
PAINT SKYBLUE (-6900 4125);
DISPLAY INVISIBLE (-6900 4125);
FORCEPROP 1 LAST PART_NUMBER TMP_QCS24702JB38
J 0
(-7075 4225);
DISPLAY 0.510638 (-7075 4225);
PAINT SKYBLUE (-7075 4225);
DISPLAY INVISIBLE (-7075 4225);
FORCEPROP 1 LAST PACK_TYPE 0402LF
J 0
(-6775 3975);
DISPLAY 0.510638 (-6775 3975);
PAINT SKYBLUE (-6775 3975);
DISPLAY INVISIBLE (-6775 3975);
FORCEADD Q_RES..1
(-7025 4300);
FORCEPROP 1 LAST LOCATION R993
J 0
(-7325 4300);
DISPLAY 0.489362 (-7325 4300);
PAINT SKYBLUE (-7325 4300);
FORCEPROP 0 LAST $SEC 1
J 0
(-7325 4350);
DISPLAY 0.680851 (-7325 4350);
PAINT MONO (-7325 4350);
DISPLAY INVISIBLE (-7325 4350);
FORCEPROP 0 LAST CDS_SEC 1
J 0
(-7325 4350);
DISPLAY 0.680851 (-7325 4350);
DISPLAY INVISIBLE (-7325 4350);
FORCEPROP 1 LASTPIN (-7125 4300) $PN 1
J 0
(-7113 4312);
DISPLAY 0.489362 (-7113 4312);
PAINT MONO (-7113 4312);
FORCEPROP 1 LASTPIN (-6925 4300) $PN 2
J 0
(-6963 4312);
DISPLAY 0.489362 (-6963 4312);
PAINT MONO (-6963 4312);
FORCEPROP 1 LAST VALUE 4.7K
J 0
(-6900 4300);
DISPLAY 0.489362 (-6900 4300);
PAINT SKYBLUE (-6900 4300);
FORCEPROP 2 LAST CDS_LIB pure_quanta
J 0
(-7025 4300);
DISPLAY INVISIBLE (-7025 4300);
FORCEPROP 1 LAST PATH I779
J 0
(-7075 4450);
DISPLAY 0.978723 (-7075 4450);
PAINT WHITE (-7075 4450);
DISPLAY INVISIBLE (-7075 4450);
FORCEPROP 1 LAST WATTAGE 1/16W
J 2
(-7050 4150);
DISPLAY 0.510638 (-7050 4150);
PAINT SKYBLUE (-7050 4150);
DISPLAY INVISIBLE (-7050 4150);
FORCEPROP 1 LAST MATERIAL CHIP
J 0
(-6925 4275);
DISPLAY 0.489362 (-6925 4275);
PAINT SKYBLUE (-6925 4275);
DISPLAY INVISIBLE (-6925 4275);
FORCEPROP 1 LAST TOLERANCE 5%
J 0
(-6900 4300);
DISPLAY 0.510638 (-6900 4300);
PAINT SKYBLUE (-6900 4300);
DISPLAY INVISIBLE (-6900 4300);
FORCEPROP 1 LAST PART_NUMBER TMP_QCS24702JB38
J 0
(-7075 4400);
DISPLAY 0.510638 (-7075 4400);
PAINT SKYBLUE (-7075 4400);
DISPLAY INVISIBLE (-7075 4400);
FORCEPROP 1 LAST PACK_TYPE 0402LF
J 0
(-6775 4150);
DISPLAY 0.510638 (-6775 4150);
PAINT SKYBLUE (-6775 4150);
DISPLAY INVISIBLE (-6775 4150);
FORCEADD Q_RES..1
(-7025 4075);
FORCEPROP 1 LAST LOCATION R1316
J 0
(-7325 4075);
DISPLAY 0.489362 (-7325 4075);
PAINT SKYBLUE (-7325 4075);
FORCEPROP 0 LAST $SEC 1
J 0
(-7325 4125);
DISPLAY 0.680851 (-7325 4125);
PAINT MONO (-7325 4125);
DISPLAY INVISIBLE (-7325 4125);
FORCEPROP 0 LAST CDS_SEC 1
J 0
(-7325 4125);
DISPLAY 0.680851 (-7325 4125);
DISPLAY INVISIBLE (-7325 4125);
FORCEPROP 1 LASTPIN (-7125 4075) $PN 1
J 0
(-7113 4087);
DISPLAY 0.489362 (-7113 4087);
PAINT MONO (-7113 4087);
FORCEPROP 1 LASTPIN (-6925 4075) $PN 2
J 0
(-6963 4087);
DISPLAY 0.489362 (-6963 4087);
PAINT MONO (-6963 4087);
FORCEPROP 1 LAST VALUE 4.7K
J 0
(-6900 4075);
DISPLAY 0.489362 (-6900 4075);
PAINT SKYBLUE (-6900 4075);
FORCEPROP 1 LAST MATERIAL EMPTY
J 0
(-6925 4050);
DISPLAY 0.489362 (-6925 4050);
PAINT RED (-6925 4050);
FORCEPROP 2 LAST CDS_LIB pure_quanta
J 0
(-7025 4075);
DISPLAY INVISIBLE (-7025 4075);
FORCEPROP 1 LAST PATH I780
J 0
(-7075 4225);
DISPLAY 0.978723 (-7075 4225);
PAINT WHITE (-7075 4225);
DISPLAY INVISIBLE (-7075 4225);
FORCEPROP 1 LAST WATTAGE 1/16W
J 2
(-7050 3925);
DISPLAY 0.510638 (-7050 3925);
PAINT SKYBLUE (-7050 3925);
DISPLAY INVISIBLE (-7050 3925);
FORCEPROP 1 LAST TOLERANCE 5%
J 0
(-6900 4075);
DISPLAY 0.510638 (-6900 4075);
PAINT SKYBLUE (-6900 4075);
DISPLAY INVISIBLE (-6900 4075);
FORCEPROP 1 LAST PART_NUMBER TMP_QCS24702JB38
J 0
(-7075 4175);
DISPLAY 0.510638 (-7075 4175);
PAINT SKYBLUE (-7075 4175);
DISPLAY INVISIBLE (-7075 4175);
FORCEPROP 1 LAST PACK_TYPE 0402LF
J 0
(-6775 3925);
DISPLAY 0.510638 (-6775 3925);
PAINT SKYBLUE (-6775 3925);
DISPLAY INVISIBLE (-6775 3925);
FORCEADD Q_RES..1
(-7025 4025);
FORCEPROP 1 LAST LOCATION R1317
J 0
(-7325 4025);
DISPLAY 0.489362 (-7325 4025);
PAINT SKYBLUE (-7325 4025);
FORCEPROP 0 LAST $SEC 1
J 0
(-7325 4075);
DISPLAY 0.680851 (-7325 4075);
PAINT MONO (-7325 4075);
DISPLAY INVISIBLE (-7325 4075);
FORCEPROP 0 LAST CDS_SEC 1
J 0
(-7325 4075);
DISPLAY 0.680851 (-7325 4075);
DISPLAY INVISIBLE (-7325 4075);
FORCEPROP 1 LASTPIN (-7125 4025) $PN 1
J 0
(-7113 4037);
DISPLAY 0.489362 (-7113 4037);
PAINT MONO (-7113 4037);
FORCEPROP 1 LASTPIN (-6925 4025) $PN 2
J 0
(-6963 4037);
DISPLAY 0.489362 (-6963 4037);
PAINT MONO (-6963 4037);
FORCEPROP 1 LAST MATERIAL EMPTY
J 0
(-6925 4000);
DISPLAY 0.489362 (-6925 4000);
PAINT RED (-6925 4000);
FORCEPROP 1 LAST VALUE 4.7K
J 0
(-6900 4025);
DISPLAY 0.489362 (-6900 4025);
PAINT SKYBLUE (-6900 4025);
FORCEPROP 2 LAST CDS_LIB pure_quanta
J 0
(-7025 4025);
DISPLAY INVISIBLE (-7025 4025);
FORCEPROP 1 LAST PATH I781
J 0
(-7075 4175);
DISPLAY 0.978723 (-7075 4175);
PAINT WHITE (-7075 4175);
DISPLAY INVISIBLE (-7075 4175);
FORCEPROP 1 LAST WATTAGE 1/16W
J 2
(-7050 3875);
DISPLAY 0.510638 (-7050 3875);
PAINT SKYBLUE (-7050 3875);
DISPLAY INVISIBLE (-7050 3875);
FORCEPROP 1 LAST TOLERANCE 5%
J 0
(-6900 4025);
DISPLAY 0.510638 (-6900 4025);
PAINT SKYBLUE (-6900 4025);
DISPLAY INVISIBLE (-6900 4025);
FORCEPROP 1 LAST PART_NUMBER TMP_QCS24702JB38
J 0
(-7075 4125);
DISPLAY 0.510638 (-7075 4125);
PAINT SKYBLUE (-7075 4125);
DISPLAY INVISIBLE (-7075 4125);
FORCEPROP 1 LAST PACK_TYPE 0402LF
J 0
(-6775 3875);
DISPLAY 0.510638 (-6775 3875);
PAINT SKYBLUE (-6775 3875);
DISPLAY INVISIBLE (-6775 3875);
FORCEADD Q_RES..1
(-7025 3925);
FORCEPROP 1 LAST LOCATION R757
J 0
(-7325 3925);
DISPLAY 0.489362 (-7325 3925);
PAINT SKYBLUE (-7325 3925);
FORCEPROP 0 LAST $SEC 1
J 0
(-7325 3975);
DISPLAY 0.680851 (-7325 3975);
PAINT MONO (-7325 3975);
DISPLAY INVISIBLE (-7325 3975);
FORCEPROP 0 LAST CDS_SEC 1
J 0
(-7325 3975);
DISPLAY 0.680851 (-7325 3975);
DISPLAY INVISIBLE (-7325 3975);
FORCEPROP 1 LASTPIN (-7125 3925) $PN 1
J 0
(-7113 3937);
DISPLAY 0.489362 (-7113 3937);
PAINT MONO (-7113 3937);
FORCEPROP 1 LASTPIN (-6925 3925) $PN 2
J 0
(-6963 3937);
DISPLAY 0.489362 (-6963 3937);
PAINT MONO (-6963 3937);
FORCEPROP 1 LAST MATERIAL EMPTY
J 0
(-6925 3900);
DISPLAY 0.489362 (-6925 3900);
PAINT RED (-6925 3900);
FORCEPROP 1 LAST VALUE 4.7K
J 0
(-6900 3925);
DISPLAY 0.489362 (-6900 3925);
PAINT SKYBLUE (-6900 3925);
FORCEPROP 2 LAST CDS_LIB pure_quanta
J 0
(-7025 3925);
DISPLAY INVISIBLE (-7025 3925);
FORCEPROP 1 LAST PATH I782
J 0
(-7075 4075);
DISPLAY 0.978723 (-7075 4075);
PAINT WHITE (-7075 4075);
DISPLAY INVISIBLE (-7075 4075);
FORCEPROP 1 LAST WATTAGE 1/16W
J 2
(-7050 3775);
DISPLAY 0.510638 (-7050 3775);
PAINT SKYBLUE (-7050 3775);
DISPLAY INVISIBLE (-7050 3775);
FORCEPROP 1 LAST TOLERANCE 5%
J 0
(-6900 3925);
DISPLAY 0.510638 (-6900 3925);
PAINT SKYBLUE (-6900 3925);
DISPLAY INVISIBLE (-6900 3925);
FORCEPROP 1 LAST PART_NUMBER TMP_QCS24702JB38
J 0
(-7075 4025);
DISPLAY 0.510638 (-7075 4025);
PAINT SKYBLUE (-7075 4025);
DISPLAY INVISIBLE (-7075 4025);
FORCEPROP 1 LAST PACK_TYPE 0402LF
J 0
(-6775 3775);
DISPLAY 0.510638 (-6775 3775);
PAINT SKYBLUE (-6775 3775);
DISPLAY INVISIBLE (-6775 3775);
FORCEADD Q_RES..1
(-7025 3875);
FORCEPROP 1 LAST LOCATION R758
J 0
(-7325 3875);
DISPLAY 0.489362 (-7325 3875);
PAINT SKYBLUE (-7325 3875);
FORCEPROP 0 LAST $SEC 1
J 0
(-7325 3925);
DISPLAY 0.680851 (-7325 3925);
PAINT MONO (-7325 3925);
DISPLAY INVISIBLE (-7325 3925);
FORCEPROP 0 LAST CDS_SEC 1
J 0
(-7325 3925);
DISPLAY 0.680851 (-7325 3925);
DISPLAY INVISIBLE (-7325 3925);
FORCEPROP 1 LASTPIN (-7125 3875) $PN 1
J 0
(-7113 3887);
DISPLAY 0.489362 (-7113 3887);
PAINT MONO (-7113 3887);
FORCEPROP 1 LASTPIN (-6925 3875) $PN 2
J 0
(-6963 3887);
DISPLAY 0.489362 (-6963 3887);
PAINT MONO (-6963 3887);
FORCEPROP 1 LAST MATERIAL EMPTY
J 0
(-6925 3850);
DISPLAY 0.489362 (-6925 3850);
PAINT RED (-6925 3850);
FORCEPROP 1 LAST VALUE 4.7K
J 0
(-6900 3875);
DISPLAY 0.489362 (-6900 3875);
PAINT SKYBLUE (-6900 3875);
FORCEPROP 2 LAST CDS_LIB pure_quanta
J 0
(-7025 3875);
DISPLAY INVISIBLE (-7025 3875);
FORCEPROP 1 LAST PATH I783
J 0
(-7075 4025);
DISPLAY 0.978723 (-7075 4025);
PAINT WHITE (-7075 4025);
DISPLAY INVISIBLE (-7075 4025);
FORCEPROP 1 LAST WATTAGE 1/16W
J 2
(-7050 3725);
DISPLAY 0.510638 (-7050 3725);
PAINT SKYBLUE (-7050 3725);
DISPLAY INVISIBLE (-7050 3725);
FORCEPROP 1 LAST TOLERANCE 5%
J 0
(-6900 3875);
DISPLAY 0.510638 (-6900 3875);
PAINT SKYBLUE (-6900 3875);
DISPLAY INVISIBLE (-6900 3875);
FORCEPROP 1 LAST PART_NUMBER TMP_QCS24702JB38
J 0
(-7075 3975);
DISPLAY 0.510638 (-7075 3975);
PAINT SKYBLUE (-7075 3975);
DISPLAY INVISIBLE (-7075 3975);
FORCEPROP 1 LAST PACK_TYPE 0402LF
J 0
(-6775 3725);
DISPLAY 0.510638 (-6775 3725);
PAINT SKYBLUE (-6775 3725);
DISPLAY INVISIBLE (-6775 3725);
FORCEADD Q_RES..1
(-7025 3825);
FORCEPROP 1 LAST LOCATION R759
J 0
(-7325 3825);
DISPLAY 0.489362 (-7325 3825);
PAINT SKYBLUE (-7325 3825);
FORCEPROP 0 LAST $SEC 1
J 0
(-7325 3875);
DISPLAY 0.680851 (-7325 3875);
PAINT MONO (-7325 3875);
DISPLAY INVISIBLE (-7325 3875);
FORCEPROP 0 LAST CDS_SEC 1
J 0
(-7325 3875);
DISPLAY 0.680851 (-7325 3875);
DISPLAY INVISIBLE (-7325 3875);
FORCEPROP 1 LASTPIN (-7125 3825) $PN 1
J 0
(-7113 3837);
DISPLAY 0.489362 (-7113 3837);
PAINT MONO (-7113 3837);
FORCEPROP 1 LASTPIN (-6925 3825) $PN 2
J 0
(-6963 3837);
DISPLAY 0.489362 (-6963 3837);
PAINT MONO (-6963 3837);
FORCEPROP 1 LAST MATERIAL EMPTY
J 0
(-6925 3800);
DISPLAY 0.489362 (-6925 3800);
PAINT RED (-6925 3800);
FORCEPROP 1 LAST VALUE 4.7K
J 0
(-6900 3825);
DISPLAY 0.489362 (-6900 3825);
PAINT SKYBLUE (-6900 3825);
FORCEPROP 2 LAST CDS_LIB pure_quanta
J 0
(-7025 3825);
DISPLAY INVISIBLE (-7025 3825);
FORCEPROP 1 LAST PATH I784
J 0
(-7075 3975);
DISPLAY 0.978723 (-7075 3975);
PAINT WHITE (-7075 3975);
DISPLAY INVISIBLE (-7075 3975);
FORCEPROP 1 LAST WATTAGE 1/16W
J 2
(-7050 3675);
DISPLAY 0.510638 (-7050 3675);
PAINT SKYBLUE (-7050 3675);
DISPLAY INVISIBLE (-7050 3675);
FORCEPROP 1 LAST TOLERANCE 5%
J 0
(-6900 3825);
DISPLAY 0.510638 (-6900 3825);
PAINT SKYBLUE (-6900 3825);
DISPLAY INVISIBLE (-6900 3825);
FORCEPROP 1 LAST PART_NUMBER TMP_QCS24702JB38
J 0
(-7075 3925);
DISPLAY 0.510638 (-7075 3925);
PAINT SKYBLUE (-7075 3925);
DISPLAY INVISIBLE (-7075 3925);
FORCEPROP 1 LAST PACK_TYPE 0402LF
J 0
(-6775 3675);
DISPLAY 0.510638 (-6775 3675);
PAINT SKYBLUE (-6775 3675);
DISPLAY INVISIBLE (-6775 3675);
FORCEADD Q_RES..1
(-7025 3775);
FORCEPROP 1 LAST LOCATION R951
J 0
(-7325 3775);
DISPLAY 0.489362 (-7325 3775);
PAINT SKYBLUE (-7325 3775);
FORCEPROP 0 LAST $SEC 1
J 0
(-7325 3825);
DISPLAY 0.680851 (-7325 3825);
PAINT MONO (-7325 3825);
DISPLAY INVISIBLE (-7325 3825);
FORCEPROP 0 LAST CDS_SEC 1
J 0
(-7325 3825);
DISPLAY 0.680851 (-7325 3825);
DISPLAY INVISIBLE (-7325 3825);
FORCEPROP 1 LASTPIN (-7125 3775) $PN 1
J 0
(-7113 3787);
DISPLAY 0.489362 (-7113 3787);
PAINT MONO (-7113 3787);
FORCEPROP 1 LASTPIN (-6925 3775) $PN 2
J 0
(-6963 3787);
DISPLAY 0.489362 (-6963 3787);
PAINT MONO (-6963 3787);
FORCEPROP 1 LAST MATERIAL EMPTY
J 0
(-6925 3750);
DISPLAY 0.489362 (-6925 3750);
PAINT RED (-6925 3750);
FORCEPROP 1 LAST VALUE 4.7K
J 0
(-6900 3775);
DISPLAY 0.489362 (-6900 3775);
PAINT SKYBLUE (-6900 3775);
FORCEPROP 2 LAST CDS_LIB pure_quanta
J 0
(-7025 3775);
DISPLAY INVISIBLE (-7025 3775);
FORCEPROP 1 LAST PATH I785
J 0
(-7075 3925);
DISPLAY 0.978723 (-7075 3925);
PAINT WHITE (-7075 3925);
DISPLAY INVISIBLE (-7075 3925);
FORCEPROP 1 LAST WATTAGE 1/16W
J 2
(-7050 3625);
DISPLAY 0.510638 (-7050 3625);
PAINT SKYBLUE (-7050 3625);
DISPLAY INVISIBLE (-7050 3625);
FORCEPROP 1 LAST TOLERANCE 5%
J 0
(-6900 3775);
DISPLAY 0.510638 (-6900 3775);
PAINT SKYBLUE (-6900 3775);
DISPLAY INVISIBLE (-6900 3775);
FORCEPROP 1 LAST PART_NUMBER TMP_QCS24702JB38
J 0
(-7075 3875);
DISPLAY 0.510638 (-7075 3875);
PAINT SKYBLUE (-7075 3875);
DISPLAY INVISIBLE (-7075 3875);
FORCEPROP 1 LAST PACK_TYPE 0402LF
J 0
(-6775 3625);
DISPLAY 0.510638 (-6775 3625);
PAINT SKYBLUE (-6775 3625);
DISPLAY INVISIBLE (-6775 3625);
FORCEADD Q_RES..1
(-7025 3625);
FORCEPROP 1 LAST LOCATION R1071
J 0
(-7325 3625);
DISPLAY 0.489362 (-7325 3625);
PAINT SKYBLUE (-7325 3625);
FORCEPROP 0 LAST $SEC 1
J 0
(-7325 3675);
DISPLAY 0.680851 (-7325 3675);
PAINT MONO (-7325 3675);
DISPLAY INVISIBLE (-7325 3675);
FORCEPROP 0 LAST CDS_SEC 1
J 0
(-7325 3675);
DISPLAY 0.680851 (-7325 3675);
DISPLAY INVISIBLE (-7325 3675);
FORCEPROP 1 LASTPIN (-7125 3625) $PN 1
J 0
(-7113 3637);
DISPLAY 0.489362 (-7113 3637);
PAINT MONO (-7113 3637);
FORCEPROP 1 LASTPIN (-6925 3625) $PN 2
J 0
(-6963 3637);
DISPLAY 0.489362 (-6963 3637);
PAINT MONO (-6963 3637);
FORCEPROP 1 LAST MATERIAL EMPTY
J 0
(-6925 3600);
DISPLAY 0.489362 (-6925 3600);
PAINT RED (-6925 3600);
FORCEPROP 1 LAST VALUE 4.7K
J 0
(-6900 3625);
DISPLAY 0.489362 (-6900 3625);
PAINT SKYBLUE (-6900 3625);
FORCEPROP 2 LAST CDS_LIB pure_quanta
J 0
(-7025 3625);
DISPLAY INVISIBLE (-7025 3625);
FORCEPROP 1 LAST PATH I795
J 0
(-7075 3775);
DISPLAY 0.978723 (-7075 3775);
PAINT WHITE (-7075 3775);
DISPLAY INVISIBLE (-7075 3775);
FORCEPROP 1 LAST WATTAGE 1/16W
J 2
(-7050 3475);
DISPLAY 0.510638 (-7050 3475);
PAINT SKYBLUE (-7050 3475);
DISPLAY INVISIBLE (-7050 3475);
FORCEPROP 1 LAST TOLERANCE 5%
J 0
(-6900 3625);
DISPLAY 0.510638 (-6900 3625);
PAINT SKYBLUE (-6900 3625);
DISPLAY INVISIBLE (-6900 3625);
FORCEPROP 1 LAST PART_NUMBER TMP_QCS24702JB38
J 0
(-7075 3725);
DISPLAY 0.510638 (-7075 3725);
PAINT SKYBLUE (-7075 3725);
DISPLAY INVISIBLE (-7075 3725);
FORCEPROP 1 LAST PACK_TYPE 0402LF
J 0
(-6775 3475);
DISPLAY 0.510638 (-6775 3475);
PAINT SKYBLUE (-6775 3475);
DISPLAY INVISIBLE (-6775 3475);
FORCEADD Q_RES..1
(-7025 3575);
FORCEPROP 1 LAST LOCATION R1195
J 0
(-7325 3575);
DISPLAY 0.489362 (-7325 3575);
PAINT SKYBLUE (-7325 3575);
FORCEPROP 0 LAST $SEC 1
J 0
(-7325 3625);
DISPLAY 0.680851 (-7325 3625);
PAINT MONO (-7325 3625);
DISPLAY INVISIBLE (-7325 3625);
FORCEPROP 0 LAST CDS_SEC 1
J 0
(-7325 3625);
DISPLAY 0.680851 (-7325 3625);
DISPLAY INVISIBLE (-7325 3625);
FORCEPROP 1 LASTPIN (-7125 3575) $PN 1
J 0
(-7113 3587);
DISPLAY 0.489362 (-7113 3587);
PAINT MONO (-7113 3587);
FORCEPROP 1 LASTPIN (-6925 3575) $PN 2
J 0
(-6963 3587);
DISPLAY 0.489362 (-6963 3587);
PAINT MONO (-6963 3587);
FORCEPROP 1 LAST MATERIAL EMPTY
J 0
(-6925 3550);
DISPLAY 0.489362 (-6925 3550);
PAINT RED (-6925 3550);
FORCEPROP 1 LAST VALUE 4.7K
J 0
(-6900 3575);
DISPLAY 0.489362 (-6900 3575);
PAINT SKYBLUE (-6900 3575);
FORCEPROP 2 LAST CDS_LIB pure_quanta
J 0
(-7025 3575);
DISPLAY INVISIBLE (-7025 3575);
FORCEPROP 1 LAST PATH I796
J 0
(-7075 3725);
DISPLAY 0.978723 (-7075 3725);
PAINT WHITE (-7075 3725);
DISPLAY INVISIBLE (-7075 3725);
FORCEPROP 1 LAST WATTAGE 1/16W
J 2
(-7050 3425);
DISPLAY 0.510638 (-7050 3425);
PAINT SKYBLUE (-7050 3425);
DISPLAY INVISIBLE (-7050 3425);
FORCEPROP 1 LAST TOLERANCE 5%
J 0
(-6900 3575);
DISPLAY 0.510638 (-6900 3575);
PAINT SKYBLUE (-6900 3575);
DISPLAY INVISIBLE (-6900 3575);
FORCEPROP 1 LAST PART_NUMBER TMP_QCS24702JB38
J 0
(-7075 3675);
DISPLAY 0.510638 (-7075 3675);
PAINT SKYBLUE (-7075 3675);
DISPLAY INVISIBLE (-7075 3675);
FORCEPROP 1 LAST PACK_TYPE 0402LF
J 0
(-6775 3425);
DISPLAY 0.510638 (-6775 3425);
PAINT SKYBLUE (-6775 3425);
DISPLAY INVISIBLE (-6775 3425);
FORCEADD OFFPAGE..5
(-8175 5825);
FORCEPROP 2 LAST $XR1 80 
J 0
(-8550 5825);
DISPLAY 0.638298 (-8550 5825);
PAINT MONO (-8550 5825);
FORCEPROP 2 LAST $XR0 162 
J 0
(-8460 5825);
DISPLAY 0.638298 (-8460 5825);
PAINT MONO (-8460 5825);
FORCEPROP 2 LAST PATH I798
J 0
(-8425 5875);
DISPLAY 0.680851 (-8425 5875);
DISPLAY INVISIBLE (-8425 5875);
FORCEPROP 1 LAST COMMENT_BODY TRUE
J 0
(-8075 5750);
DISPLAY 0.872340 (-8075 5750);
PAINT GREEN (-8075 5750);
DISPLAY INVISIBLE (-8075 5750);
FORCEPROP 1 LAST OFFPAGE TRUE
J 0
(-7850 5700);
DISPLAY 0.872340 (-7850 5700);
PAINT GREEN (-7850 5700);
DISPLAY INVISIBLE (-7850 5700);
FORCEPROP 2 LAST CDS_LIB standard
J 0
(-8175 5825);
DISPLAY INVISIBLE (-8175 5825);
FORCEADD OFFPAGE..5
(-8175 5725);
FORCEPROP 2 LAST $XR1 29 
J 0
(-8519 5725);
DISPLAY 0.638298 (-8519 5725);
PAINT MONO (-8519 5725);
FORCEPROP 2 LAST $XR0 80 
J 0
(-8429 5725);
DISPLAY 0.638298 (-8429 5725);
PAINT MONO (-8429 5725);
FORCEPROP 2 LAST PATH I799
J 0
(-8375 5775);
DISPLAY 0.680851 (-8375 5775);
DISPLAY INVISIBLE (-8375 5775);
FORCEPROP 1 LAST COMMENT_BODY TRUE
J 0
(-8075 5650);
DISPLAY 0.872340 (-8075 5650);
PAINT GREEN (-8075 5650);
DISPLAY INVISIBLE (-8075 5650);
FORCEPROP 1 LAST OFFPAGE TRUE
J 0
(-7850 5600);
DISPLAY 0.872340 (-7850 5600);
PAINT GREEN (-7850 5600);
DISPLAY INVISIBLE (-7850 5600);
FORCEPROP 2 LAST CDS_LIB standard
J 0
(-8175 5725);
DISPLAY INVISIBLE (-8175 5725);
FORCEADD OFFPAGE..5
(-8175 5775);
FORCEPROP 2 LAST $XR1 80 
J 0
(-8550 5775);
DISPLAY 0.638298 (-8550 5775);
PAINT MONO (-8550 5775);
FORCEPROP 2 LAST $XR0 162 
J 0
(-8460 5775);
DISPLAY 0.638298 (-8460 5775);
PAINT MONO (-8460 5775);
FORCEPROP 2 LAST PATH I800
J 0
(-8425 5825);
DISPLAY 0.680851 (-8425 5825);
DISPLAY INVISIBLE (-8425 5825);
FORCEPROP 1 LAST COMMENT_BODY TRUE
J 0
(-8075 5700);
DISPLAY 0.872340 (-8075 5700);
PAINT GREEN (-8075 5700);
DISPLAY INVISIBLE (-8075 5700);
FORCEPROP 1 LAST OFFPAGE TRUE
J 0
(-7850 5650);
DISPLAY 0.872340 (-7850 5650);
PAINT GREEN (-7850 5650);
DISPLAY INVISIBLE (-7850 5650);
FORCEPROP 2 LAST CDS_LIB standard
J 0
(-8175 5775);
DISPLAY INVISIBLE (-8175 5775);
FORCEADD OFFPAGE..5
(-8175 5350);
FORCEPROP 2 LAST $XR1 81 
J 0
(-8550 5350);
DISPLAY 0.638298 (-8550 5350);
PAINT MONO (-8550 5350);
FORCEPROP 2 LAST $XR0 183 
J 0
(-8460 5350);
DISPLAY 0.638298 (-8460 5350);
PAINT MONO (-8460 5350);
FORCEPROP 2 LAST PATH I801
J 0
(-8425 5400);
DISPLAY 0.680851 (-8425 5400);
DISPLAY INVISIBLE (-8425 5400);
FORCEPROP 1 LAST COMMENT_BODY TRUE
J 0
(-8075 5275);
DISPLAY 0.872340 (-8075 5275);
PAINT GREEN (-8075 5275);
DISPLAY INVISIBLE (-8075 5275);
FORCEPROP 1 LAST OFFPAGE TRUE
J 0
(-7850 5225);
DISPLAY 0.872340 (-7850 5225);
PAINT GREEN (-7850 5225);
DISPLAY INVISIBLE (-7850 5225);
FORCEPROP 2 LAST CDS_LIB standard
J 0
(-8175 5350);
DISPLAY INVISIBLE (-8175 5350);
FORCEADD OFFPAGE..5
(-8175 5550);
FORCEPROP 2 LAST $XR1 80 
J 0
(-8550 5550);
DISPLAY 0.638298 (-8550 5550);
PAINT MONO (-8550 5550);
FORCEPROP 2 LAST $XR0 169 
J 0
(-8460 5550);
DISPLAY 0.638298 (-8460 5550);
PAINT MONO (-8460 5550);
FORCEPROP 2 LAST PATH I802
J 0
(-8425 5600);
DISPLAY 0.680851 (-8425 5600);
DISPLAY INVISIBLE (-8425 5600);
FORCEPROP 1 LAST COMMENT_BODY TRUE
J 0
(-8075 5475);
DISPLAY 0.872340 (-8075 5475);
PAINT GREEN (-8075 5475);
DISPLAY INVISIBLE (-8075 5475);
FORCEPROP 1 LAST OFFPAGE TRUE
J 0
(-7850 5425);
DISPLAY 0.872340 (-7850 5425);
PAINT GREEN (-7850 5425);
DISPLAY INVISIBLE (-7850 5425);
FORCEPROP 2 LAST CDS_LIB standard
J 0
(-8175 5550);
DISPLAY INVISIBLE (-8175 5550);
FORCEADD OFFPAGE..5
(-8175 5500);
FORCEPROP 2 LAST $XR1 81 
J 0
(-8550 5500);
DISPLAY 0.638298 (-8550 5500);
PAINT MONO (-8550 5500);
FORCEPROP 2 LAST $XR0 176 
J 0
(-8460 5500);
DISPLAY 0.638298 (-8460 5500);
PAINT MONO (-8460 5500);
FORCEPROP 2 LAST PATH I803
J 0
(-8425 5550);
DISPLAY 0.680851 (-8425 5550);
DISPLAY INVISIBLE (-8425 5550);
FORCEPROP 1 LAST COMMENT_BODY TRUE
J 0
(-8075 5425);
DISPLAY 0.872340 (-8075 5425);
PAINT GREEN (-8075 5425);
DISPLAY INVISIBLE (-8075 5425);
FORCEPROP 1 LAST OFFPAGE TRUE
J 0
(-7850 5375);
DISPLAY 0.872340 (-7850 5375);
PAINT GREEN (-7850 5375);
DISPLAY INVISIBLE (-7850 5375);
FORCEPROP 2 LAST CDS_LIB standard
J 0
(-8175 5500);
DISPLAY INVISIBLE (-8175 5500);
FORCEADD OFFPAGE..5
(-8175 5450);
FORCEPROP 2 LAST $XR1 81 
J 0
(-8550 5450);
DISPLAY 0.638298 (-8550 5450);
PAINT MONO (-8550 5450);
FORCEPROP 2 LAST $XR0 186 
J 0
(-8460 5450);
DISPLAY 0.638298 (-8460 5450);
PAINT MONO (-8460 5450);
FORCEPROP 2 LAST PATH I804
J 0
(-8425 5500);
DISPLAY 0.680851 (-8425 5500);
DISPLAY INVISIBLE (-8425 5500);
FORCEPROP 1 LAST COMMENT_BODY TRUE
J 0
(-8075 5375);
DISPLAY 0.872340 (-8075 5375);
PAINT GREEN (-8075 5375);
DISPLAY INVISIBLE (-8075 5375);
FORCEPROP 1 LAST OFFPAGE TRUE
J 0
(-7850 5325);
DISPLAY 0.872340 (-7850 5325);
PAINT GREEN (-7850 5325);
DISPLAY INVISIBLE (-7850 5325);
FORCEPROP 2 LAST CDS_LIB standard
J 0
(-8175 5450);
DISPLAY INVISIBLE (-8175 5450);
FORCEADD OFFPAGE..5
(-8175 5400);
FORCEPROP 2 LAST $XR1 81 
J 0
(-8550 5400);
DISPLAY 0.638298 (-8550 5400);
PAINT MONO (-8550 5400);
FORCEPROP 2 LAST $XR0 193 
J 0
(-8460 5400);
DISPLAY 0.638298 (-8460 5400);
PAINT MONO (-8460 5400);
FORCEPROP 2 LAST PATH I805
J 0
(-8425 5450);
DISPLAY 0.680851 (-8425 5450);
DISPLAY INVISIBLE (-8425 5450);
FORCEPROP 1 LAST COMMENT_BODY TRUE
J 0
(-8075 5325);
DISPLAY 0.872340 (-8075 5325);
PAINT GREEN (-8075 5325);
DISPLAY INVISIBLE (-8075 5325);
FORCEPROP 1 LAST OFFPAGE TRUE
J 0
(-7850 5275);
DISPLAY 0.872340 (-7850 5275);
PAINT GREEN (-7850 5275);
DISPLAY INVISIBLE (-7850 5275);
FORCEPROP 2 LAST CDS_LIB standard
J 0
(-8175 5400);
DISPLAY INVISIBLE (-8175 5400);
FORCEADD OFFPAGE..5
(-8175 5300);
FORCEPROP 2 LAST $XR1 81 
J 0
(-8550 5300);
DISPLAY 0.638298 (-8550 5300);
PAINT MONO (-8550 5300);
FORCEPROP 2 LAST $XR0 200 
J 0
(-8460 5300);
DISPLAY 0.638298 (-8460 5300);
PAINT MONO (-8460 5300);
FORCEPROP 2 LAST PATH I808
J 0
(-8425 5350);
DISPLAY 0.680851 (-8425 5350);
DISPLAY INVISIBLE (-8425 5350);
FORCEPROP 1 LAST COMMENT_BODY TRUE
J 0
(-8075 5225);
DISPLAY 0.872340 (-8075 5225);
PAINT GREEN (-8075 5225);
DISPLAY INVISIBLE (-8075 5225);
FORCEPROP 1 LAST OFFPAGE TRUE
J 0
(-7850 5175);
DISPLAY 0.872340 (-7850 5175);
PAINT GREEN (-7850 5175);
DISPLAY INVISIBLE (-7850 5175);
FORCEPROP 2 LAST CDS_LIB standard
J 0
(-8175 5300);
DISPLAY INVISIBLE (-8175 5300);
FORCEADD OFFPAGE..5
(-8175 5100);
FORCEPROP 2 LAST $XR1 79 
J 0
(-8550 5100);
DISPLAY 0.638298 (-8550 5100);
PAINT MONO (-8550 5100);
FORCEPROP 2 LAST $XR0 158 
J 0
(-8460 5100);
DISPLAY 0.638298 (-8460 5100);
PAINT MONO (-8460 5100);
FORCEPROP 2 LAST PATH I809
J 0
(-8425 5150);
DISPLAY 0.680851 (-8425 5150);
DISPLAY INVISIBLE (-8425 5150);
FORCEPROP 1 LAST COMMENT_BODY TRUE
J 0
(-8075 5025);
DISPLAY 0.872340 (-8075 5025);
PAINT GREEN (-8075 5025);
DISPLAY INVISIBLE (-8075 5025);
FORCEPROP 1 LAST OFFPAGE TRUE
J 0
(-7850 4975);
DISPLAY 0.872340 (-7850 4975);
PAINT GREEN (-7850 4975);
DISPLAY INVISIBLE (-7850 4975);
FORCEPROP 2 LAST CDS_LIB standard
J 0
(-8175 5100);
DISPLAY INVISIBLE (-8175 5100);
FORCEADD OFFPAGE..5
(-8175 4975);
FORCEPROP 2 LAST $XR1 131 
J 0
(-8549 4975);
DISPLAY 0.638298 (-8549 4975);
PAINT MONO (-8549 4975);
FORCEPROP 2 LAST $XR0 80 
J 0
(-8429 4975);
DISPLAY 0.638298 (-8429 4975);
PAINT MONO (-8429 4975);
FORCEPROP 2 LAST PATH I810
J 0
(-8425 5025);
DISPLAY 0.680851 (-8425 5025);
DISPLAY INVISIBLE (-8425 5025);
FORCEPROP 1 LAST COMMENT_BODY TRUE
J 0
(-8075 4900);
DISPLAY 0.872340 (-8075 4900);
PAINT GREEN (-8075 4900);
DISPLAY INVISIBLE (-8075 4900);
FORCEPROP 1 LAST OFFPAGE TRUE
J 0
(-7850 4850);
DISPLAY 0.872340 (-7850 4850);
PAINT GREEN (-7850 4850);
DISPLAY INVISIBLE (-7850 4850);
FORCEPROP 2 LAST CDS_LIB standard
J 0
(-8175 4975);
DISPLAY INVISIBLE (-8175 4975);
FORCEADD OFFPAGE..5
(-8175 5025);
FORCEPROP 2 LAST $XR1 131 
J 0
(-8549 5025);
DISPLAY 0.638298 (-8549 5025);
PAINT MONO (-8549 5025);
FORCEPROP 2 LAST $XR0 80 
J 0
(-8429 5025);
DISPLAY 0.638298 (-8429 5025);
PAINT MONO (-8429 5025);
FORCEPROP 2 LAST PATH I811
J 0
(-8425 5075);
DISPLAY 0.680851 (-8425 5075);
DISPLAY INVISIBLE (-8425 5075);
FORCEPROP 1 LAST COMMENT_BODY TRUE
J 0
(-8075 4950);
DISPLAY 0.872340 (-8075 4950);
PAINT GREEN (-8075 4950);
DISPLAY INVISIBLE (-8075 4950);
FORCEPROP 1 LAST OFFPAGE TRUE
J 0
(-7850 4900);
DISPLAY 0.872340 (-7850 4900);
PAINT GREEN (-7850 4900);
DISPLAY INVISIBLE (-7850 4900);
FORCEPROP 2 LAST CDS_LIB standard
J 0
(-8175 5025);
DISPLAY INVISIBLE (-8175 5025);
FORCEADD OFFPAGE..5
(-8175 4725);
FORCEPROP 2 LAST $XR1 80 
J 0
(-8550 4725);
DISPLAY 0.638298 (-8550 4725);
PAINT MONO (-8550 4725);
FORCEPROP 2 LAST $XR0 115 
J 0
(-8460 4725);
DISPLAY 0.638298 (-8460 4725);
PAINT MONO (-8460 4725);
FORCEPROP 2 LAST CDS_LIB standard
J 0
(-8175 4725);
DISPLAY INVISIBLE (-8175 4725);
FORCEPROP 2 LAST PATH I812
J 0
(-8425 4775);
DISPLAY 0.680851 (-8425 4775);
DISPLAY INVISIBLE (-8425 4775);
FORCEPROP 1 LAST COMMENT_BODY TRUE
J 0
(-8075 4650);
DISPLAY 0.872340 (-8075 4650);
PAINT GREEN (-8075 4650);
DISPLAY INVISIBLE (-8075 4650);
FORCEPROP 1 LAST OFFPAGE TRUE
J 0
(-7850 4600);
DISPLAY 0.872340 (-7850 4600);
PAINT GREEN (-7850 4600);
DISPLAY INVISIBLE (-7850 4600);
FORCEADD OFFPAGE..5
(-8175 4675);
FORCEPROP 2 LAST $XR1 80 
J 0
(-8550 4675);
DISPLAY 0.638298 (-8550 4675);
PAINT MONO (-8550 4675);
FORCEPROP 2 LAST $XR0 115 
J 0
(-8460 4675);
DISPLAY 0.638298 (-8460 4675);
PAINT MONO (-8460 4675);
FORCEPROP 2 LAST CDS_LIB standard
J 0
(-8175 4675);
DISPLAY INVISIBLE (-8175 4675);
FORCEPROP 2 LAST PATH I813
J 0
(-8425 4725);
DISPLAY 0.680851 (-8425 4725);
DISPLAY INVISIBLE (-8425 4725);
FORCEPROP 1 LAST COMMENT_BODY TRUE
J 0
(-8075 4600);
DISPLAY 0.872340 (-8075 4600);
PAINT GREEN (-8075 4600);
DISPLAY INVISIBLE (-8075 4600);
FORCEPROP 1 LAST OFFPAGE TRUE
J 0
(-7850 4550);
DISPLAY 0.872340 (-7850 4550);
PAINT GREEN (-7850 4550);
DISPLAY INVISIBLE (-7850 4550);
FORCEADD OFFPAGE..5
(-8175 4625);
FORCEPROP 2 LAST $XR1 81 
J 0
(-8550 4625);
DISPLAY 0.638298 (-8550 4625);
PAINT MONO (-8550 4625);
FORCEPROP 2 LAST $XR0 116 
J 0
(-8460 4625);
DISPLAY 0.638298 (-8460 4625);
PAINT MONO (-8460 4625);
FORCEPROP 2 LAST CDS_LIB standard
J 0
(-8175 4625);
DISPLAY INVISIBLE (-8175 4625);
FORCEPROP 2 LAST PATH I814
J 0
(-8425 4675);
DISPLAY 0.680851 (-8425 4675);
DISPLAY INVISIBLE (-8425 4675);
FORCEPROP 1 LAST COMMENT_BODY TRUE
J 0
(-8075 4550);
DISPLAY 0.872340 (-8075 4550);
PAINT GREEN (-8075 4550);
DISPLAY INVISIBLE (-8075 4550);
FORCEPROP 1 LAST OFFPAGE TRUE
J 0
(-7850 4500);
DISPLAY 0.872340 (-7850 4500);
PAINT GREEN (-7850 4500);
DISPLAY INVISIBLE (-7850 4500);
FORCEADD OFFPAGE..5
(-8175 4450);
FORCEPROP 2 LAST $XR1 81 
J 0
(-8550 4450);
DISPLAY 0.638298 (-8550 4450);
PAINT MONO (-8550 4450);
FORCEPROP 2 LAST $XR0 126 
J 0
(-8460 4450);
DISPLAY 0.638298 (-8460 4450);
PAINT MONO (-8460 4450);
FORCEPROP 2 LAST PATH I815
J 0
(-8425 4500);
DISPLAY 0.680851 (-8425 4500);
DISPLAY INVISIBLE (-8425 4500);
FORCEPROP 1 LAST COMMENT_BODY TRUE
J 0
(-8075 4375);
DISPLAY 0.872340 (-8075 4375);
PAINT GREEN (-8075 4375);
DISPLAY INVISIBLE (-8075 4375);
FORCEPROP 1 LAST OFFPAGE TRUE
J 0
(-7850 4325);
DISPLAY 0.872340 (-7850 4325);
PAINT GREEN (-7850 4325);
DISPLAY INVISIBLE (-7850 4325);
FORCEPROP 2 LAST CDS_LIB standard
J 0
(-8175 4450);
DISPLAY INVISIBLE (-8175 4450);
FORCEADD OFFPAGE..5
(-8175 4500);
FORCEPROP 2 LAST $XR1 81 
J 0
(-8550 4500);
DISPLAY 0.638298 (-8550 4500);
PAINT MONO (-8550 4500);
FORCEPROP 2 LAST $XR0 125 
J 0
(-8460 4500);
DISPLAY 0.638298 (-8460 4500);
PAINT MONO (-8460 4500);
FORCEPROP 2 LAST PATH I816
J 0
(-8425 4550);
DISPLAY 0.680851 (-8425 4550);
DISPLAY INVISIBLE (-8425 4550);
FORCEPROP 1 LAST COMMENT_BODY TRUE
J 0
(-8075 4425);
DISPLAY 0.872340 (-8075 4425);
PAINT GREEN (-8075 4425);
DISPLAY INVISIBLE (-8075 4425);
FORCEPROP 1 LAST OFFPAGE TRUE
J 0
(-7850 4375);
DISPLAY 0.872340 (-7850 4375);
PAINT GREEN (-7850 4375);
DISPLAY INVISIBLE (-7850 4375);
FORCEPROP 2 LAST CDS_LIB standard
J 0
(-8175 4500);
DISPLAY INVISIBLE (-8175 4500);
FORCEADD OFFPAGE..5
(-8175 4550);
FORCEPROP 2 LAST $XR1 81 
J 0
(-8550 4550);
DISPLAY 0.638298 (-8550 4550);
PAINT MONO (-8550 4550);
FORCEPROP 2 LAST $XR0 124 
J 0
(-8460 4550);
DISPLAY 0.638298 (-8460 4550);
PAINT MONO (-8460 4550);
FORCEPROP 2 LAST PATH I817
J 0
(-8425 4600);
DISPLAY 0.680851 (-8425 4600);
DISPLAY INVISIBLE (-8425 4600);
FORCEPROP 1 LAST COMMENT_BODY TRUE
J 0
(-8075 4475);
DISPLAY 0.872340 (-8075 4475);
PAINT GREEN (-8075 4475);
DISPLAY INVISIBLE (-8075 4475);
FORCEPROP 1 LAST OFFPAGE TRUE
J 0
(-7850 4425);
DISPLAY 0.872340 (-7850 4425);
PAINT GREEN (-7850 4425);
DISPLAY INVISIBLE (-7850 4425);
FORCEPROP 2 LAST CDS_LIB standard
J 0
(-8175 4550);
DISPLAY INVISIBLE (-8175 4550);
FORCEADD OFFPAGE..5
(-8200 4300);
FORCEPROP 2 LAST $XR1 133 
J 0
(-8574 4300);
DISPLAY 0.638298 (-8574 4300);
PAINT MONO (-8574 4300);
FORCEPROP 2 LAST $XR0 79 
J 0
(-8454 4300);
DISPLAY 0.638298 (-8454 4300);
PAINT MONO (-8454 4300);
FORCEPROP 2 LAST PATH I818
J 0
(-8450 4350);
DISPLAY 0.680851 (-8450 4350);
DISPLAY INVISIBLE (-8450 4350);
FORCEPROP 1 LAST COMMENT_BODY TRUE
J 0
(-8100 4225);
DISPLAY 0.872340 (-8100 4225);
PAINT GREEN (-8100 4225);
DISPLAY INVISIBLE (-8100 4225);
FORCEPROP 1 LAST OFFPAGE TRUE
J 0
(-7875 4175);
DISPLAY 0.872340 (-7875 4175);
PAINT GREEN (-7875 4175);
DISPLAY INVISIBLE (-7875 4175);
FORCEPROP 2 LAST CDS_LIB standard
J 0
(-8200 4300);
DISPLAY INVISIBLE (-8200 4300);
FORCEADD OFFPAGE..5
(-8200 4125);
FORCEPROP 2 LAST $XR1 206 
J 0
(-8574 4125);
DISPLAY 0.638298 (-8574 4125);
PAINT MONO (-8574 4125);
FORCEPROP 2 LAST $XR0 80 
J 0
(-8454 4125);
DISPLAY 0.638298 (-8454 4125);
PAINT MONO (-8454 4125);
FORCEPROP 2 LAST PATH I819
J 0
(-8450 4175);
DISPLAY 0.680851 (-8450 4175);
DISPLAY INVISIBLE (-8450 4175);
FORCEPROP 1 LAST COMMENT_BODY TRUE
J 0
(-8100 4050);
DISPLAY 0.872340 (-8100 4050);
PAINT GREEN (-8100 4050);
DISPLAY INVISIBLE (-8100 4050);
FORCEPROP 1 LAST OFFPAGE TRUE
J 0
(-7875 4000);
DISPLAY 0.872340 (-7875 4000);
PAINT GREEN (-7875 4000);
DISPLAY INVISIBLE (-7875 4000);
FORCEPROP 2 LAST CDS_LIB standard
J 0
(-8200 4125);
DISPLAY INVISIBLE (-8200 4125);
FORCEADD OFFPAGE..5
(-8200 4175);
FORCEPROP 2 LAST $XR1 205 
J 0
(-8574 4175);
DISPLAY 0.638298 (-8574 4175);
PAINT MONO (-8574 4175);
FORCEPROP 2 LAST $XR0 80 
J 0
(-8454 4175);
DISPLAY 0.638298 (-8454 4175);
PAINT MONO (-8454 4175);
FORCEPROP 2 LAST PATH I820
J 0
(-8450 4225);
DISPLAY 0.680851 (-8450 4225);
DISPLAY INVISIBLE (-8450 4225);
FORCEPROP 1 LAST COMMENT_BODY TRUE
J 0
(-8100 4100);
DISPLAY 0.872340 (-8100 4100);
PAINT GREEN (-8100 4100);
DISPLAY INVISIBLE (-8100 4100);
FORCEPROP 1 LAST OFFPAGE TRUE
J 0
(-7875 4050);
DISPLAY 0.872340 (-7875 4050);
PAINT GREEN (-7875 4050);
DISPLAY INVISIBLE (-7875 4050);
FORCEPROP 2 LAST CDS_LIB standard
J 0
(-8200 4175);
DISPLAY INVISIBLE (-8200 4175);
FORCEADD OFFPAGE..5
(-8175 4400);
FORCEPROP 2 LAST $XR1 81 
J 0
(-8550 4400);
DISPLAY 0.638298 (-8550 4400);
PAINT MONO (-8550 4400);
FORCEPROP 2 LAST $XR0 127 
J 0
(-8460 4400);
DISPLAY 0.638298 (-8460 4400);
PAINT MONO (-8460 4400);
FORCEPROP 2 LAST PATH I821
J 0
(-8425 4450);
DISPLAY 0.680851 (-8425 4450);
DISPLAY INVISIBLE (-8425 4450);
FORCEPROP 1 LAST COMMENT_BODY TRUE
J 0
(-8075 4325);
DISPLAY 0.872340 (-8075 4325);
PAINT GREEN (-8075 4325);
DISPLAY INVISIBLE (-8075 4325);
FORCEPROP 1 LAST OFFPAGE TRUE
J 0
(-7850 4275);
DISPLAY 0.872340 (-7850 4275);
PAINT GREEN (-7850 4275);
DISPLAY INVISIBLE (-7850 4275);
FORCEPROP 2 LAST CDS_LIB standard
J 0
(-8175 4400);
DISPLAY INVISIBLE (-8175 4400);
FORCEADD OFFPAGE..5
(-8200 4075);
FORCEPROP 2 LAST $XR1 207 
J 0
(-8574 4075);
DISPLAY 0.638298 (-8574 4075);
PAINT MONO (-8574 4075);
FORCEPROP 2 LAST $XR0 80 
J 0
(-8454 4075);
DISPLAY 0.638298 (-8454 4075);
PAINT MONO (-8454 4075);
FORCEPROP 2 LAST PATH I822
J 0
(-8450 4125);
DISPLAY 0.680851 (-8450 4125);
DISPLAY INVISIBLE (-8450 4125);
FORCEPROP 1 LAST COMMENT_BODY TRUE
J 0
(-8100 4000);
DISPLAY 0.872340 (-8100 4000);
PAINT GREEN (-8100 4000);
DISPLAY INVISIBLE (-8100 4000);
FORCEPROP 1 LAST OFFPAGE TRUE
J 0
(-7875 3950);
DISPLAY 0.872340 (-7875 3950);
PAINT GREEN (-7875 3950);
DISPLAY INVISIBLE (-7875 3950);
FORCEPROP 2 LAST CDS_LIB standard
J 0
(-8200 4075);
DISPLAY INVISIBLE (-8200 4075);
FORCEADD OFFPAGE..5
(-8200 4025);
FORCEPROP 2 LAST $XR1 208 
J 0
(-8574 4025);
DISPLAY 0.638298 (-8574 4025);
PAINT MONO (-8574 4025);
FORCEPROP 2 LAST $XR0 80 
J 0
(-8454 4025);
DISPLAY 0.638298 (-8454 4025);
PAINT MONO (-8454 4025);
FORCEPROP 2 LAST PATH I823
J 0
(-8450 4075);
DISPLAY 0.680851 (-8450 4075);
DISPLAY INVISIBLE (-8450 4075);
FORCEPROP 1 LAST COMMENT_BODY TRUE
J 0
(-8100 3950);
DISPLAY 0.872340 (-8100 3950);
PAINT GREEN (-8100 3950);
DISPLAY INVISIBLE (-8100 3950);
FORCEPROP 1 LAST OFFPAGE TRUE
J 0
(-7875 3900);
DISPLAY 0.872340 (-7875 3900);
PAINT GREEN (-7875 3900);
DISPLAY INVISIBLE (-7875 3900);
FORCEPROP 2 LAST CDS_LIB standard
J 0
(-8200 4025);
DISPLAY INVISIBLE (-8200 4025);
FORCEADD OFFPAGE..5
(-8200 3925);
FORCEPROP 2 LAST $XR1 205 
J 0
(-8574 3925);
DISPLAY 0.638298 (-8574 3925);
PAINT MONO (-8574 3925);
FORCEPROP 2 LAST $XR0 80 
J 0
(-8454 3925);
DISPLAY 0.638298 (-8454 3925);
PAINT MONO (-8454 3925);
FORCEPROP 2 LAST PATH I824
J 0
(-8450 3975);
DISPLAY 0.680851 (-8450 3975);
DISPLAY INVISIBLE (-8450 3975);
FORCEPROP 1 LAST COMMENT_BODY TRUE
J 0
(-8100 3850);
DISPLAY 0.872340 (-8100 3850);
PAINT GREEN (-8100 3850);
DISPLAY INVISIBLE (-8100 3850);
FORCEPROP 1 LAST OFFPAGE TRUE
J 0
(-7875 3800);
DISPLAY 0.872340 (-7875 3800);
PAINT GREEN (-7875 3800);
DISPLAY INVISIBLE (-7875 3800);
FORCEPROP 2 LAST CDS_LIB standard
J 0
(-8200 3925);
DISPLAY INVISIBLE (-8200 3925);
FORCEADD OFFPAGE..5
(-8200 3875);
FORCEPROP 2 LAST $XR1 206 
J 0
(-8574 3875);
DISPLAY 0.638298 (-8574 3875);
PAINT MONO (-8574 3875);
FORCEPROP 2 LAST $XR0 80 
J 0
(-8454 3875);
DISPLAY 0.638298 (-8454 3875);
PAINT MONO (-8454 3875);
FORCEPROP 2 LAST PATH I825
J 0
(-8450 3925);
DISPLAY 0.680851 (-8450 3925);
DISPLAY INVISIBLE (-8450 3925);
FORCEPROP 1 LAST COMMENT_BODY TRUE
J 0
(-8100 3800);
DISPLAY 0.872340 (-8100 3800);
PAINT GREEN (-8100 3800);
DISPLAY INVISIBLE (-8100 3800);
FORCEPROP 1 LAST OFFPAGE TRUE
J 0
(-7875 3750);
DISPLAY 0.872340 (-7875 3750);
PAINT GREEN (-7875 3750);
DISPLAY INVISIBLE (-7875 3750);
FORCEPROP 2 LAST CDS_LIB standard
J 0
(-8200 3875);
DISPLAY INVISIBLE (-8200 3875);
FORCEADD OFFPAGE..5
(-8200 3775);
FORCEPROP 2 LAST $XR1 208 
J 0
(-8574 3775);
DISPLAY 0.638298 (-8574 3775);
PAINT MONO (-8574 3775);
FORCEPROP 2 LAST $XR0 80 
J 0
(-8454 3775);
DISPLAY 0.638298 (-8454 3775);
PAINT MONO (-8454 3775);
FORCEPROP 2 LAST PATH I826
J 0
(-8450 3825);
DISPLAY 0.680851 (-8450 3825);
DISPLAY INVISIBLE (-8450 3825);
FORCEPROP 1 LAST COMMENT_BODY TRUE
J 0
(-8100 3700);
DISPLAY 0.872340 (-8100 3700);
PAINT GREEN (-8100 3700);
DISPLAY INVISIBLE (-8100 3700);
FORCEPROP 1 LAST OFFPAGE TRUE
J 0
(-7875 3650);
DISPLAY 0.872340 (-7875 3650);
PAINT GREEN (-7875 3650);
DISPLAY INVISIBLE (-7875 3650);
FORCEPROP 2 LAST CDS_LIB standard
J 0
(-8200 3775);
DISPLAY INVISIBLE (-8200 3775);
FORCEADD OFFPAGE..5
(-8200 3825);
FORCEPROP 2 LAST $XR1 207 
J 0
(-8574 3825);
DISPLAY 0.638298 (-8574 3825);
PAINT MONO (-8574 3825);
FORCEPROP 2 LAST $XR0 80 
J 0
(-8454 3825);
DISPLAY 0.638298 (-8454 3825);
PAINT MONO (-8454 3825);
FORCEPROP 2 LAST PATH I827
J 0
(-8450 3875);
DISPLAY 0.680851 (-8450 3875);
DISPLAY INVISIBLE (-8450 3875);
FORCEPROP 1 LAST COMMENT_BODY TRUE
J 0
(-8100 3750);
DISPLAY 0.872340 (-8100 3750);
PAINT GREEN (-8100 3750);
DISPLAY INVISIBLE (-8100 3750);
FORCEPROP 1 LAST OFFPAGE TRUE
J 0
(-7875 3700);
DISPLAY 0.872340 (-7875 3700);
PAINT GREEN (-7875 3700);
DISPLAY INVISIBLE (-7875 3700);
FORCEPROP 2 LAST CDS_LIB standard
J 0
(-8200 3825);
DISPLAY INVISIBLE (-8200 3825);
FORCEADD OFFPAGE..5
(-8200 3625);
FORCEPROP 2 LAST $XR1 209 
J 0
(-8574 3625);
DISPLAY 0.638298 (-8574 3625);
PAINT MONO (-8574 3625);
FORCEPROP 2 LAST $XR0 79 
J 0
(-8454 3625);
DISPLAY 0.638298 (-8454 3625);
PAINT MONO (-8454 3625);
FORCEPROP 2 LAST PATH I836
J 0
(-8450 3675);
DISPLAY 0.680851 (-8450 3675);
DISPLAY INVISIBLE (-8450 3675);
FORCEPROP 1 LAST COMMENT_BODY TRUE
J 0
(-8100 3550);
DISPLAY 0.872340 (-8100 3550);
PAINT GREEN (-8100 3550);
DISPLAY INVISIBLE (-8100 3550);
FORCEPROP 1 LAST OFFPAGE TRUE
J 0
(-7875 3500);
DISPLAY 0.872340 (-7875 3500);
PAINT GREEN (-7875 3500);
DISPLAY INVISIBLE (-7875 3500);
FORCEPROP 2 LAST CDS_LIB standard
J 0
(-8200 3625);
DISPLAY INVISIBLE (-8200 3625);
FORCEADD OFFPAGE..5
(-8200 3575);
FORCEPROP 2 LAST $XR1 209 
J 0
(-8574 3575);
DISPLAY 0.638298 (-8574 3575);
PAINT MONO (-8574 3575);
FORCEPROP 2 LAST $XR0 79 
J 0
(-8454 3575);
DISPLAY 0.638298 (-8454 3575);
PAINT MONO (-8454 3575);
FORCEPROP 2 LAST PATH I838
J 0
(-8450 3625);
DISPLAY 0.680851 (-8450 3625);
DISPLAY INVISIBLE (-8450 3625);
FORCEPROP 1 LAST COMMENT_BODY TRUE
J 0
(-8100 3500);
DISPLAY 0.872340 (-8100 3500);
PAINT GREEN (-8100 3500);
DISPLAY INVISIBLE (-8100 3500);
FORCEPROP 1 LAST OFFPAGE TRUE
J 0
(-7875 3450);
DISPLAY 0.872340 (-7875 3450);
PAINT GREEN (-7875 3450);
DISPLAY INVISIBLE (-7875 3450);
FORCEPROP 2 LAST CDS_LIB standard
J 0
(-8200 3575);
DISPLAY INVISIBLE (-8200 3575);
FORCEADD Q_RES..1
(-7025 5875);
FORCEPROP 1 LAST LOCATION R1520
J 0
(-7250 5875);
DISPLAY 0.489362 (-7250 5875);
PAINT SKYBLUE (-7250 5875);
FORCEPROP 0 LAST $SEC 1
J 0
(-6900 5900);
DISPLAY 0.680851 (-6900 5900);
PAINT MONO (-6900 5900);
DISPLAY INVISIBLE (-6900 5900);
FORCEPROP 0 LAST CDS_SEC 1
J 0
(-6900 5900);
DISPLAY 0.680851 (-6900 5900);
DISPLAY INVISIBLE (-6900 5900);
FORCEPROP 1 LASTPIN (-7125 5875) $PN 1
J 0
(-7113 5887);
DISPLAY 0.489362 (-7113 5887);
PAINT MONO (-7113 5887);
FORCEPROP 1 LASTPIN (-6925 5875) $PN 2
J 0
(-6963 5887);
DISPLAY 0.489362 (-6963 5887);
PAINT MONO (-6963 5887);
FORCEPROP 1 LAST VALUE 4.7K
J 0
(-6900 5875);
DISPLAY 0.489362 (-6900 5875);
PAINT SKYBLUE (-6900 5875);
FORCEPROP 2 LAST CDS_LIB pure_quanta
J 0
(-7025 5875);
DISPLAY INVISIBLE (-7025 5875);
FORCEPROP 1 LAST PATH I839
J 0
(-7075 6025);
DISPLAY 0.978723 (-7075 6025);
PAINT WHITE (-7075 6025);
DISPLAY INVISIBLE (-7075 6025);
FORCEPROP 1 LAST WATTAGE 1/16W
J 2
(-7050 5725);
DISPLAY 0.510638 (-7050 5725);
PAINT SKYBLUE (-7050 5725);
DISPLAY INVISIBLE (-7050 5725);
FORCEPROP 1 LAST MATERIAL CHIP
J 0
(-6925 5850);
DISPLAY 0.489362 (-6925 5850);
PAINT SKYBLUE (-6925 5850);
DISPLAY INVISIBLE (-6925 5850);
FORCEPROP 1 LAST TOLERANCE 5%
J 0
(-6900 5875);
DISPLAY 0.510638 (-6900 5875);
PAINT SKYBLUE (-6900 5875);
DISPLAY INVISIBLE (-6900 5875);
FORCEPROP 1 LAST PART_NUMBER TMP_QCS24702JB38
J 0
(-7075 5975);
DISPLAY 0.510638 (-7075 5975);
PAINT SKYBLUE (-7075 5975);
DISPLAY INVISIBLE (-7075 5975);
FORCEPROP 1 LAST PACK_TYPE 0402LF
J 0
(-6775 5725);
DISPLAY 0.510638 (-6775 5725);
PAINT SKYBLUE (-6775 5725);
DISPLAY INVISIBLE (-6775 5725);
FORCEADD Q_RES..1
(-7025 5925);
FORCEPROP 1 LAST LOCATION R1519
J 0
(-7250 5925);
DISPLAY 0.489362 (-7250 5925);
PAINT SKYBLUE (-7250 5925);
FORCEPROP 0 LAST $SEC 1
J 0
(-7250 5975);
DISPLAY 0.680851 (-7250 5975);
PAINT MONO (-7250 5975);
DISPLAY INVISIBLE (-7250 5975);
FORCEPROP 0 LAST CDS_SEC 1
J 0
(-7250 5975);
DISPLAY 0.680851 (-7250 5975);
DISPLAY INVISIBLE (-7250 5975);
FORCEPROP 1 LASTPIN (-7125 5925) $PN 1
J 0
(-7113 5937);
DISPLAY 0.489362 (-7113 5937);
PAINT MONO (-7113 5937);
FORCEPROP 1 LASTPIN (-6925 5925) $PN 2
J 0
(-6963 5937);
DISPLAY 0.489362 (-6963 5937);
PAINT MONO (-6963 5937);
FORCEPROP 1 LAST VALUE 4.7K
J 0
(-6900 5925);
DISPLAY 0.489362 (-6900 5925);
PAINT SKYBLUE (-6900 5925);
FORCEPROP 2 LAST CDS_LIB pure_quanta
J 0
(-7025 5925);
DISPLAY INVISIBLE (-7025 5925);
FORCEPROP 1 LAST PATH I840
J 0
(-7075 6075);
DISPLAY 0.978723 (-7075 6075);
PAINT WHITE (-7075 6075);
DISPLAY INVISIBLE (-7075 6075);
FORCEPROP 1 LAST WATTAGE 1/16W
J 2
(-7050 5775);
DISPLAY 0.510638 (-7050 5775);
PAINT SKYBLUE (-7050 5775);
DISPLAY INVISIBLE (-7050 5775);
FORCEPROP 1 LAST MATERIAL CHIP
J 0
(-6925 5900);
DISPLAY 0.489362 (-6925 5900);
PAINT SKYBLUE (-6925 5900);
DISPLAY INVISIBLE (-6925 5900);
FORCEPROP 1 LAST TOLERANCE 5%
J 0
(-6900 5925);
DISPLAY 0.510638 (-6900 5925);
PAINT SKYBLUE (-6900 5925);
DISPLAY INVISIBLE (-6900 5925);
FORCEPROP 1 LAST PART_NUMBER TMP_QCS24702JB38
J 0
(-7075 6025);
DISPLAY 0.510638 (-7075 6025);
PAINT SKYBLUE (-7075 6025);
DISPLAY INVISIBLE (-7075 6025);
FORCEPROP 1 LAST PACK_TYPE 0402LF
J 0
(-6775 5775);
DISPLAY 0.510638 (-6775 5775);
PAINT SKYBLUE (-6775 5775);
DISPLAY INVISIBLE (-6775 5775);
FORCEADD Q_RES..1
(-7025 5975);
FORCEPROP 1 LAST LOCATION R1518
J 0
(-7250 5975);
DISPLAY 0.489362 (-7250 5975);
PAINT SKYBLUE (-7250 5975);
FORCEPROP 0 LAST $SEC 1
J 0
(-7250 6025);
DISPLAY 0.680851 (-7250 6025);
PAINT MONO (-7250 6025);
DISPLAY INVISIBLE (-7250 6025);
FORCEPROP 0 LAST CDS_SEC 1
J 0
(-7250 6025);
DISPLAY 0.680851 (-7250 6025);
DISPLAY INVISIBLE (-7250 6025);
FORCEPROP 1 LASTPIN (-7125 5975) $PN 1
J 0
(-7113 5987);
DISPLAY 0.489362 (-7113 5987);
PAINT MONO (-7113 5987);
FORCEPROP 1 LASTPIN (-6925 5975) $PN 2
J 0
(-6963 5987);
DISPLAY 0.489362 (-6963 5987);
PAINT MONO (-6963 5987);
FORCEPROP 1 LAST VALUE 4.7K
J 0
(-6900 5975);
DISPLAY 0.489362 (-6900 5975);
PAINT SKYBLUE (-6900 5975);
FORCEPROP 2 LAST CDS_LIB pure_quanta
J 0
(-7025 5975);
DISPLAY INVISIBLE (-7025 5975);
FORCEPROP 1 LAST PATH I841
J 0
(-7075 6125);
DISPLAY 0.978723 (-7075 6125);
PAINT WHITE (-7075 6125);
DISPLAY INVISIBLE (-7075 6125);
FORCEPROP 1 LAST WATTAGE 1/16W
J 2
(-7050 5825);
DISPLAY 0.510638 (-7050 5825);
PAINT SKYBLUE (-7050 5825);
DISPLAY INVISIBLE (-7050 5825);
FORCEPROP 1 LAST MATERIAL CHIP
J 0
(-6925 5950);
DISPLAY 0.489362 (-6925 5950);
PAINT SKYBLUE (-6925 5950);
DISPLAY INVISIBLE (-6925 5950);
FORCEPROP 1 LAST TOLERANCE 5%
J 0
(-6900 5975);
DISPLAY 0.510638 (-6900 5975);
PAINT SKYBLUE (-6900 5975);
DISPLAY INVISIBLE (-6900 5975);
FORCEPROP 1 LAST PART_NUMBER TMP_QCS24702JB38
J 0
(-7075 6075);
DISPLAY 0.510638 (-7075 6075);
PAINT SKYBLUE (-7075 6075);
DISPLAY INVISIBLE (-7075 6075);
FORCEPROP 1 LAST PACK_TYPE 0402LF
J 0
(-6775 5825);
DISPLAY 0.510638 (-6775 5825);
PAINT SKYBLUE (-6775 5825);
DISPLAY INVISIBLE (-6775 5825);
FORCEADD Q_RES..1
(-7025 6025);
FORCEPROP 1 LAST LOCATION R1517
J 0
(-7250 6025);
DISPLAY 0.489362 (-7250 6025);
PAINT SKYBLUE (-7250 6025);
FORCEPROP 0 LAST $SEC 1
J 0
(-7250 6075);
DISPLAY 0.680851 (-7250 6075);
PAINT MONO (-7250 6075);
DISPLAY INVISIBLE (-7250 6075);
FORCEPROP 0 LAST CDS_SEC 1
J 0
(-7250 6075);
DISPLAY 0.680851 (-7250 6075);
DISPLAY INVISIBLE (-7250 6075);
FORCEPROP 1 LASTPIN (-7125 6025) $PN 1
J 0
(-7113 6037);
DISPLAY 0.489362 (-7113 6037);
PAINT MONO (-7113 6037);
FORCEPROP 1 LASTPIN (-6925 6025) $PN 2
J 0
(-6963 6037);
DISPLAY 0.489362 (-6963 6037);
PAINT MONO (-6963 6037);
FORCEPROP 1 LAST VALUE 4.7K
J 0
(-6900 6025);
DISPLAY 0.489362 (-6900 6025);
PAINT SKYBLUE (-6900 6025);
FORCEPROP 2 LAST CDS_LIB pure_quanta
J 0
(-7025 6025);
DISPLAY INVISIBLE (-7025 6025);
FORCEPROP 1 LAST PATH I842
J 0
(-7075 6175);
DISPLAY 0.978723 (-7075 6175);
PAINT WHITE (-7075 6175);
DISPLAY INVISIBLE (-7075 6175);
FORCEPROP 1 LAST WATTAGE 1/16W
J 2
(-7050 5875);
DISPLAY 0.510638 (-7050 5875);
PAINT SKYBLUE (-7050 5875);
DISPLAY INVISIBLE (-7050 5875);
FORCEPROP 1 LAST MATERIAL CHIP
J 0
(-6925 6000);
DISPLAY 0.489362 (-6925 6000);
PAINT SKYBLUE (-6925 6000);
DISPLAY INVISIBLE (-6925 6000);
FORCEPROP 1 LAST TOLERANCE 5%
J 0
(-6900 6025);
DISPLAY 0.510638 (-6900 6025);
PAINT SKYBLUE (-6900 6025);
DISPLAY INVISIBLE (-6900 6025);
FORCEPROP 1 LAST PART_NUMBER TMP_QCS24702JB38
J 0
(-7075 6125);
DISPLAY 0.510638 (-7075 6125);
PAINT SKYBLUE (-7075 6125);
DISPLAY INVISIBLE (-7075 6125);
FORCEPROP 1 LAST PACK_TYPE 0402LF
J 0
(-6775 5875);
DISPLAY 0.510638 (-6775 5875);
PAINT SKYBLUE (-6775 5875);
DISPLAY INVISIBLE (-6775 5875);
FORCEADD Q_RES..1
(-7025 6075);
FORCEPROP 1 LAST LOCATION R1516
J 0
(-7250 6075);
DISPLAY 0.489362 (-7250 6075);
PAINT SKYBLUE (-7250 6075);
FORCEPROP 0 LAST $SEC 1
J 0
(-7250 6125);
DISPLAY 0.680851 (-7250 6125);
PAINT MONO (-7250 6125);
DISPLAY INVISIBLE (-7250 6125);
FORCEPROP 0 LAST CDS_SEC 1
J 0
(-7250 6125);
DISPLAY 0.680851 (-7250 6125);
DISPLAY INVISIBLE (-7250 6125);
FORCEPROP 1 LASTPIN (-7125 6075) $PN 1
J 0
(-7113 6087);
DISPLAY 0.489362 (-7113 6087);
PAINT MONO (-7113 6087);
FORCEPROP 1 LASTPIN (-6925 6075) $PN 2
J 0
(-6963 6087);
DISPLAY 0.489362 (-6963 6087);
PAINT MONO (-6963 6087);
FORCEPROP 1 LAST VALUE 4.7K
J 0
(-6900 6075);
DISPLAY 0.489362 (-6900 6075);
PAINT SKYBLUE (-6900 6075);
FORCEPROP 2 LAST CDS_LIB pure_quanta
J 0
(-7025 6075);
DISPLAY INVISIBLE (-7025 6075);
FORCEPROP 1 LAST PATH I843
J 0
(-7075 6225);
DISPLAY 0.978723 (-7075 6225);
PAINT WHITE (-7075 6225);
DISPLAY INVISIBLE (-7075 6225);
FORCEPROP 1 LAST WATTAGE 1/16W
J 2
(-7050 5925);
DISPLAY 0.510638 (-7050 5925);
PAINT SKYBLUE (-7050 5925);
DISPLAY INVISIBLE (-7050 5925);
FORCEPROP 1 LAST MATERIAL CHIP
J 0
(-6925 6050);
DISPLAY 0.489362 (-6925 6050);
PAINT SKYBLUE (-6925 6050);
DISPLAY INVISIBLE (-6925 6050);
FORCEPROP 1 LAST TOLERANCE 5%
J 0
(-6900 6075);
DISPLAY 0.510638 (-6900 6075);
PAINT SKYBLUE (-6900 6075);
DISPLAY INVISIBLE (-6900 6075);
FORCEPROP 1 LAST PART_NUMBER TMP_QCS24702JB38
J 0
(-7075 6175);
DISPLAY 0.510638 (-7075 6175);
PAINT SKYBLUE (-7075 6175);
DISPLAY INVISIBLE (-7075 6175);
FORCEPROP 1 LAST PACK_TYPE 0402LF
J 0
(-6775 5925);
DISPLAY 0.510638 (-6775 5925);
PAINT SKYBLUE (-6775 5925);
DISPLAY INVISIBLE (-6775 5925);
FORCEADD Q_RES..1
(-7025 6125);
FORCEPROP 1 LAST LOCATION R1515
J 0
(-7250 6125);
DISPLAY 0.489362 (-7250 6125);
PAINT SKYBLUE (-7250 6125);
FORCEPROP 0 LAST $SEC 1
J 0
(-7250 6175);
DISPLAY 0.680851 (-7250 6175);
PAINT MONO (-7250 6175);
DISPLAY INVISIBLE (-7250 6175);
FORCEPROP 0 LAST CDS_SEC 1
J 0
(-7250 6175);
DISPLAY 0.680851 (-7250 6175);
DISPLAY INVISIBLE (-7250 6175);
FORCEPROP 1 LASTPIN (-7125 6125) $PN 1
J 0
(-7113 6137);
DISPLAY 0.489362 (-7113 6137);
PAINT MONO (-7113 6137);
FORCEPROP 1 LASTPIN (-6925 6125) $PN 2
J 0
(-6963 6137);
DISPLAY 0.489362 (-6963 6137);
PAINT MONO (-6963 6137);
FORCEPROP 1 LAST VALUE 4.7K
J 0
(-6900 6125);
DISPLAY 0.489362 (-6900 6125);
PAINT SKYBLUE (-6900 6125);
FORCEPROP 2 LAST CDS_LIB pure_quanta
J 0
(-7025 6125);
DISPLAY INVISIBLE (-7025 6125);
FORCEPROP 1 LAST PATH I844
J 0
(-7075 6275);
DISPLAY 0.978723 (-7075 6275);
PAINT WHITE (-7075 6275);
DISPLAY INVISIBLE (-7075 6275);
FORCEPROP 1 LAST WATTAGE 1/16W
J 2
(-7050 5975);
DISPLAY 0.510638 (-7050 5975);
PAINT SKYBLUE (-7050 5975);
DISPLAY INVISIBLE (-7050 5975);
FORCEPROP 1 LAST MATERIAL CHIP
J 0
(-6925 6100);
DISPLAY 0.489362 (-6925 6100);
PAINT SKYBLUE (-6925 6100);
DISPLAY INVISIBLE (-6925 6100);
FORCEPROP 1 LAST TOLERANCE 5%
J 0
(-6900 6125);
DISPLAY 0.510638 (-6900 6125);
PAINT SKYBLUE (-6900 6125);
DISPLAY INVISIBLE (-6900 6125);
FORCEPROP 1 LAST PART_NUMBER TMP_QCS24702JB38
J 0
(-7075 6225);
DISPLAY 0.510638 (-7075 6225);
PAINT SKYBLUE (-7075 6225);
DISPLAY INVISIBLE (-7075 6225);
FORCEPROP 1 LAST PACK_TYPE 0402LF
J 0
(-6775 5975);
DISPLAY 0.510638 (-6775 5975);
PAINT SKYBLUE (-6775 5975);
DISPLAY INVISIBLE (-6775 5975);
FORCEADD OFFPAGE..5
(-8175 5875);
FORCEPROP 2 LAST $XR1 80 
J 0
(-8550 5875);
DISPLAY 0.638298 (-8550 5875);
PAINT MONO (-8550 5875);
FORCEPROP 2 LAST $XR0 114 
J 0
(-8460 5875);
DISPLAY 0.638298 (-8460 5875);
PAINT MONO (-8460 5875);
FORCEPROP 2 LAST PATH I845
J 0
(-8125 5950);
DISPLAY 0.680851 (-8125 5950);
DISPLAY INVISIBLE (-8125 5950);
FORCEPROP 1 LAST COMMENT_BODY TRUE
J 0
(-8075 5800);
DISPLAY 0.872340 (-8075 5800);
PAINT GREEN (-8075 5800);
DISPLAY INVISIBLE (-8075 5800);
FORCEPROP 1 LAST OFFPAGE TRUE
J 0
(-7850 5750);
DISPLAY 0.872340 (-7850 5750);
PAINT GREEN (-7850 5750);
DISPLAY INVISIBLE (-7850 5750);
FORCEPROP 2 LAST CDS_LIB standard
J 0
(-8175 5875);
DISPLAY INVISIBLE (-8175 5875);
FORCEADD OFFPAGE..5
(-8175 5925);
FORCEPROP 2 LAST $XR1 80 
J 0
(-8550 5925);
DISPLAY 0.638298 (-8550 5925);
PAINT MONO (-8550 5925);
FORCEPROP 2 LAST $XR0 115 
J 0
(-8460 5925);
DISPLAY 0.638298 (-8460 5925);
PAINT MONO (-8460 5925);
FORCEPROP 2 LAST PATH I846
J 0
(-8125 6000);
DISPLAY 0.680851 (-8125 6000);
DISPLAY INVISIBLE (-8125 6000);
FORCEPROP 1 LAST COMMENT_BODY TRUE
J 0
(-8075 5850);
DISPLAY 0.872340 (-8075 5850);
PAINT GREEN (-8075 5850);
DISPLAY INVISIBLE (-8075 5850);
FORCEPROP 1 LAST OFFPAGE TRUE
J 0
(-7850 5800);
DISPLAY 0.872340 (-7850 5800);
PAINT GREEN (-7850 5800);
DISPLAY INVISIBLE (-7850 5800);
FORCEPROP 2 LAST CDS_LIB standard
J 0
(-8175 5925);
DISPLAY INVISIBLE (-8175 5925);
FORCEADD OFFPAGE..5
(-8175 5975);
FORCEPROP 2 LAST $XR1 80 
J 0
(-8550 5975);
DISPLAY 0.638298 (-8550 5975);
PAINT MONO (-8550 5975);
FORCEPROP 2 LAST $XR0 114 
J 0
(-8460 5975);
DISPLAY 0.638298 (-8460 5975);
PAINT MONO (-8460 5975);
FORCEPROP 2 LAST PATH I847
J 0
(-8125 6050);
DISPLAY 0.680851 (-8125 6050);
DISPLAY INVISIBLE (-8125 6050);
FORCEPROP 1 LAST COMMENT_BODY TRUE
J 0
(-8075 5900);
DISPLAY 0.872340 (-8075 5900);
PAINT GREEN (-8075 5900);
DISPLAY INVISIBLE (-8075 5900);
FORCEPROP 1 LAST OFFPAGE TRUE
J 0
(-7850 5850);
DISPLAY 0.872340 (-7850 5850);
PAINT GREEN (-7850 5850);
DISPLAY INVISIBLE (-7850 5850);
FORCEPROP 2 LAST CDS_LIB standard
J 0
(-8175 5975);
DISPLAY INVISIBLE (-8175 5975);
FORCEADD OFFPAGE..5
(-8175 6025);
FORCEPROP 2 LAST $XR1 80 
J 0
(-8550 6025);
DISPLAY 0.638298 (-8550 6025);
PAINT MONO (-8550 6025);
FORCEPROP 2 LAST $XR0 114 
J 0
(-8460 6025);
DISPLAY 0.638298 (-8460 6025);
PAINT MONO (-8460 6025);
FORCEPROP 2 LAST PATH I848
J 0
(-8125 6100);
DISPLAY 0.680851 (-8125 6100);
DISPLAY INVISIBLE (-8125 6100);
FORCEPROP 1 LAST COMMENT_BODY TRUE
J 0
(-8075 5950);
DISPLAY 0.872340 (-8075 5950);
PAINT GREEN (-8075 5950);
DISPLAY INVISIBLE (-8075 5950);
FORCEPROP 1 LAST OFFPAGE TRUE
J 0
(-7850 5900);
DISPLAY 0.872340 (-7850 5900);
PAINT GREEN (-7850 5900);
DISPLAY INVISIBLE (-7850 5900);
FORCEPROP 2 LAST CDS_LIB standard
J 0
(-8175 6025);
DISPLAY INVISIBLE (-8175 6025);
FORCEADD OFFPAGE..5
(-8175 6125);
FORCEPROP 2 LAST $XR1 80 
J 0
(-8550 6125);
DISPLAY 0.638298 (-8550 6125);
PAINT MONO (-8550 6125);
FORCEPROP 2 LAST $XR0 115 
J 0
(-8460 6125);
DISPLAY 0.638298 (-8460 6125);
PAINT MONO (-8460 6125);
FORCEPROP 2 LAST PATH I849
J 0
(-8125 6200);
DISPLAY 0.680851 (-8125 6200);
DISPLAY INVISIBLE (-8125 6200);
FORCEPROP 1 LAST COMMENT_BODY TRUE
J 0
(-8075 6050);
DISPLAY 0.872340 (-8075 6050);
PAINT GREEN (-8075 6050);
DISPLAY INVISIBLE (-8075 6050);
FORCEPROP 1 LAST OFFPAGE TRUE
J 0
(-7850 6000);
DISPLAY 0.872340 (-7850 6000);
PAINT GREEN (-7850 6000);
DISPLAY INVISIBLE (-7850 6000);
FORCEPROP 2 LAST CDS_LIB standard
J 0
(-8175 6125);
DISPLAY INVISIBLE (-8175 6125);
FORCEADD OFFPAGE..5
(-8175 6075);
FORCEPROP 2 LAST $XR1 80 
J 0
(-8550 6075);
DISPLAY 0.638298 (-8550 6075);
PAINT MONO (-8550 6075);
FORCEPROP 2 LAST $XR0 115 
J 0
(-8460 6075);
DISPLAY 0.638298 (-8460 6075);
PAINT MONO (-8460 6075);
FORCEPROP 2 LAST PATH I850
J 0
(-8125 6150);
DISPLAY 0.680851 (-8125 6150);
DISPLAY INVISIBLE (-8125 6150);
FORCEPROP 1 LAST COMMENT_BODY TRUE
J 0
(-8075 6000);
DISPLAY 0.872340 (-8075 6000);
PAINT GREEN (-8075 6000);
DISPLAY INVISIBLE (-8075 6000);
FORCEPROP 1 LAST OFFPAGE TRUE
J 0
(-7850 5950);
DISPLAY 0.872340 (-7850 5950);
PAINT GREEN (-7850 5950);
DISPLAY INVISIBLE (-7850 5950);
FORCEPROP 2 LAST CDS_LIB standard
J 0
(-8175 6075);
DISPLAY INVISIBLE (-8175 6075);
FORCEADD Q_RES..1
(-7050 2975);
FORCEPROP 1 LAST LOCATION R64
J 0
(-7250 2975);
DISPLAY 0.489362 (-7250 2975);
PAINT SKYBLUE (-7250 2975);
FORCEPROP 0 LAST $SEC 1
J 2
(-7200 3025);
DISPLAY 0.680851 (-7200 3025);
PAINT MONO (-7200 3025);
DISPLAY INVISIBLE (-7200 3025);
FORCEPROP 0 LAST CDS_SEC 1
J 2
(-7200 3025);
DISPLAY 1.021277 (-7200 3025);
DISPLAY INVISIBLE (-7200 3025);
FORCEPROP 1 LASTPIN (-7150 2975) $PN 1
J 0
(-7138 2987);
DISPLAY 0.489362 (-7138 2987);
PAINT MONO (-7138 2987);
FORCEPROP 1 LASTPIN (-6950 2975) $PN 2
J 0
(-6988 2987);
DISPLAY 0.489362 (-6988 2987);
PAINT MONO (-6988 2987);
FORCEPROP 1 LAST VALUE 1K
J 0
(-6950 2975);
DISPLAY 0.489362 (-6950 2975);
PAINT SKYBLUE (-6950 2975);
FORCEPROP 2 LAST CDS_LIB pure_quanta
J 2
(-7050 2975);
DISPLAY INVISIBLE (-7050 2975);
FORCEPROP 1 LAST PATH I909
J 0
(-7100 3125);
DISPLAY 0.978723 (-7100 3125);
PAINT WHITE (-7100 3125);
DISPLAY INVISIBLE (-7100 3125);
FORCEPROP 1 LAST WATTAGE 1/16W
J 2
(-7075 2825);
DISPLAY 0.510638 (-7075 2825);
PAINT SKYBLUE (-7075 2825);
DISPLAY INVISIBLE (-7075 2825);
FORCEPROP 1 LAST MATERIAL CHIP
J 0
(-6950 2950);
DISPLAY 0.489362 (-6950 2950);
PAINT SKYBLUE (-6950 2950);
DISPLAY INVISIBLE (-6950 2950);
FORCEPROP 1 LAST TOLERANCE 5%
J 0
(-6925 2975);
DISPLAY 0.510638 (-6925 2975);
PAINT SKYBLUE (-6925 2975);
DISPLAY INVISIBLE (-6925 2975);
FORCEPROP 1 LAST PART_NUMBER TMP_QCS21002JB34
J 0
(-7100 3075);
DISPLAY 0.510638 (-7100 3075);
PAINT SKYBLUE (-7100 3075);
DISPLAY INVISIBLE (-7100 3075);
FORCEPROP 1 LAST PACK_TYPE 0402LF
J 0
(-6800 2825);
DISPLAY 0.510638 (-6800 2825);
PAINT SKYBLUE (-6800 2825);
DISPLAY INVISIBLE (-6800 2825);
FORCEADD Q_RES..1
(-7050 3100);
FORCEPROP 1 LAST LOCATION R638
J 0
(-7250 3100);
DISPLAY 0.489362 (-7250 3100);
PAINT SKYBLUE (-7250 3100);
FORCEPROP 0 LAST $SEC 1
J 0
(-7200 3150);
DISPLAY 0.680851 (-7200 3150);
PAINT MONO (-7200 3150);
DISPLAY INVISIBLE (-7200 3150);
FORCEPROP 0 LAST CDS_SEC 1
J 0
(-7200 3150);
DISPLAY 1.021277 (-7200 3150);
DISPLAY INVISIBLE (-7200 3150);
FORCEPROP 1 LASTPIN (-7150 3100) $PN 1
J 0
(-7138 3112);
DISPLAY 0.489362 (-7138 3112);
PAINT MONO (-7138 3112);
FORCEPROP 1 LASTPIN (-6950 3100) $PN 2
J 0
(-6988 3112);
DISPLAY 0.489362 (-6988 3112);
PAINT MONO (-6988 3112);
FORCEPROP 1 LAST VALUE 1K
J 0
(-6950 3100);
DISPLAY 0.489362 (-6950 3100);
PAINT SKYBLUE (-6950 3100);
FORCEPROP 2 LAST CDS_LIB pure_quanta
J 0
(-7050 3100);
DISPLAY INVISIBLE (-7050 3100);
FORCEPROP 1 LAST PATH I910
J 0
(-7100 3250);
DISPLAY 0.978723 (-7100 3250);
PAINT WHITE (-7100 3250);
DISPLAY INVISIBLE (-7100 3250);
FORCEPROP 1 LAST WATTAGE 1/16W
J 2
(-7075 2950);
DISPLAY 0.510638 (-7075 2950);
PAINT SKYBLUE (-7075 2950);
DISPLAY INVISIBLE (-7075 2950);
FORCEPROP 1 LAST MATERIAL CHIP
J 0
(-6950 3075);
DISPLAY 0.489362 (-6950 3075);
PAINT SKYBLUE (-6950 3075);
DISPLAY INVISIBLE (-6950 3075);
FORCEPROP 1 LAST TOLERANCE 5%
J 0
(-6925 3100);
DISPLAY 0.510638 (-6925 3100);
PAINT SKYBLUE (-6925 3100);
DISPLAY INVISIBLE (-6925 3100);
FORCEPROP 1 LAST PART_NUMBER TMP_QCS21002JB34
J 0
(-7100 3200);
DISPLAY 0.510638 (-7100 3200);
PAINT SKYBLUE (-7100 3200);
DISPLAY INVISIBLE (-7100 3200);
FORCEPROP 1 LAST PACK_TYPE 0402LF
J 0
(-6800 2950);
DISPLAY 0.510638 (-6800 2950);
PAINT SKYBLUE (-6800 2950);
DISPLAY INVISIBLE (-6800 2950);
FORCEADD Q_RES..1
(-7050 3050);
FORCEPROP 1 LAST LOCATION R639
J 0
(-7250 3050);
DISPLAY 0.489362 (-7250 3050);
PAINT SKYBLUE (-7250 3050);
FORCEPROP 0 LAST $SEC 1
J 0
(-7200 3100);
DISPLAY 0.680851 (-7200 3100);
PAINT MONO (-7200 3100);
DISPLAY INVISIBLE (-7200 3100);
FORCEPROP 0 LAST CDS_SEC 1
J 0
(-7200 3100);
DISPLAY 1.021277 (-7200 3100);
DISPLAY INVISIBLE (-7200 3100);
FORCEPROP 1 LASTPIN (-7150 3050) $PN 1
J 0
(-7138 3062);
DISPLAY 0.489362 (-7138 3062);
PAINT MONO (-7138 3062);
FORCEPROP 1 LASTPIN (-6950 3050) $PN 2
J 0
(-6988 3062);
DISPLAY 0.489362 (-6988 3062);
PAINT MONO (-6988 3062);
FORCEPROP 1 LAST VALUE 1K
J 0
(-6950 3050);
DISPLAY 0.489362 (-6950 3050);
PAINT SKYBLUE (-6950 3050);
FORCEPROP 2 LAST CDS_LIB pure_quanta
J 0
(-7050 3050);
DISPLAY INVISIBLE (-7050 3050);
FORCEPROP 1 LAST PATH I911
J 0
(-7100 3200);
DISPLAY 0.978723 (-7100 3200);
PAINT WHITE (-7100 3200);
DISPLAY INVISIBLE (-7100 3200);
FORCEPROP 1 LAST WATTAGE 1/16W
J 2
(-7075 2900);
DISPLAY 0.510638 (-7075 2900);
PAINT SKYBLUE (-7075 2900);
DISPLAY INVISIBLE (-7075 2900);
FORCEPROP 1 LAST MATERIAL CHIP
J 0
(-6950 3025);
DISPLAY 0.489362 (-6950 3025);
PAINT SKYBLUE (-6950 3025);
DISPLAY INVISIBLE (-6950 3025);
FORCEPROP 1 LAST TOLERANCE 5%
J 0
(-6925 3050);
DISPLAY 0.510638 (-6925 3050);
PAINT SKYBLUE (-6925 3050);
DISPLAY INVISIBLE (-6925 3050);
FORCEPROP 1 LAST PART_NUMBER TMP_QCS21002JB34
J 0
(-7100 3150);
DISPLAY 0.510638 (-7100 3150);
PAINT SKYBLUE (-7100 3150);
DISPLAY INVISIBLE (-7100 3150);
FORCEPROP 1 LAST PACK_TYPE 0402LF
J 0
(-6800 2900);
DISPLAY 0.510638 (-6800 2900);
PAINT SKYBLUE (-6800 2900);
DISPLAY INVISIBLE (-6800 2900);
FORCEADD OFFPAGE..1
R 2
(-2200 3650);
FORCEPROP 2 LAST $XR1 136 
J 0
(-1924 3650);
DISPLAY 0.638298 (-1924 3650);
PAINT MONO (-1924 3650);
FORCEPROP 2 LAST $XR0 79 
J 0
(-2014 3650);
DISPLAY 0.638298 (-2014 3650);
PAINT MONO (-2014 3650);
FORCEPROP 2 LAST PATH I928
J 0
(-1900 3700);
DISPLAY 0.680851 (-1900 3700);
DISPLAY INVISIBLE (-1900 3700);
FORCEPROP 1 LAST COMMENT_BODY TRUE
J 2
(-2325 3550);
DISPLAY 0.872340 (-2325 3550);
PAINT GREEN (-2325 3550);
DISPLAY INVISIBLE (-2325 3550);
FORCEPROP 1 LAST OFFPAGE TRUE
J 2
(-2525 3525);
DISPLAY 0.872340 (-2525 3525);
PAINT GREEN (-2525 3525);
DISPLAY INVISIBLE (-2525 3525);
FORCEPROP 2 LAST CDS_LIB standard
J 0
(-2200 3650);
DISPLAY INVISIBLE (-2200 3650);
FORCEADD OFFPAGE..1
R 2
(-2200 3600);
FORCEPROP 2 LAST $XR1 136 
J 0
(-1924 3600);
DISPLAY 0.638298 (-1924 3600);
PAINT MONO (-1924 3600);
FORCEPROP 2 LAST $XR0 79 
J 0
(-2014 3600);
DISPLAY 0.638298 (-2014 3600);
PAINT MONO (-2014 3600);
FORCEPROP 2 LAST PATH I929
J 0
(-1900 3650);
DISPLAY 0.680851 (-1900 3650);
DISPLAY INVISIBLE (-1900 3650);
FORCEPROP 1 LAST COMMENT_BODY TRUE
J 2
(-2325 3500);
DISPLAY 0.872340 (-2325 3500);
PAINT GREEN (-2325 3500);
DISPLAY INVISIBLE (-2325 3500);
FORCEPROP 1 LAST OFFPAGE TRUE
J 2
(-2525 3475);
DISPLAY 0.872340 (-2525 3475);
PAINT GREEN (-2525 3475);
DISPLAY INVISIBLE (-2525 3475);
FORCEPROP 2 LAST CDS_LIB standard
J 0
(-2200 3600);
DISPLAY INVISIBLE (-2200 3600);
FORCEADD OFFPAGE..1
R 2
(-2200 3550);
FORCEPROP 2 LAST $XR1 136 
J 0
(-1924 3550);
DISPLAY 0.638298 (-1924 3550);
PAINT MONO (-1924 3550);
FORCEPROP 2 LAST $XR0 79 
J 0
(-2014 3550);
DISPLAY 0.638298 (-2014 3550);
PAINT MONO (-2014 3550);
FORCEPROP 2 LAST PATH I930
J 0
(-1900 3600);
DISPLAY 0.680851 (-1900 3600);
DISPLAY INVISIBLE (-1900 3600);
FORCEPROP 1 LAST COMMENT_BODY TRUE
J 2
(-2325 3450);
DISPLAY 0.872340 (-2325 3450);
PAINT GREEN (-2325 3450);
DISPLAY INVISIBLE (-2325 3450);
FORCEPROP 1 LAST OFFPAGE TRUE
J 2
(-2525 3425);
DISPLAY 0.872340 (-2525 3425);
PAINT GREEN (-2525 3425);
DISPLAY INVISIBLE (-2525 3425);
FORCEPROP 2 LAST CDS_LIB standard
J 0
(-2200 3550);
DISPLAY INVISIBLE (-2200 3550);
FORCEADD OFFPAGE..1
R 2
(-2200 3500);
FORCEPROP 2 LAST $XR1 136 
J 0
(-1924 3500);
DISPLAY 0.638298 (-1924 3500);
PAINT MONO (-1924 3500);
FORCEPROP 2 LAST $XR0 79 
J 0
(-2014 3500);
DISPLAY 0.638298 (-2014 3500);
PAINT MONO (-2014 3500);
FORCEPROP 2 LAST PATH I931
J 0
(-1900 3550);
DISPLAY 0.680851 (-1900 3550);
DISPLAY INVISIBLE (-1900 3550);
FORCEPROP 1 LAST COMMENT_BODY TRUE
J 2
(-2325 3400);
DISPLAY 0.872340 (-2325 3400);
PAINT GREEN (-2325 3400);
DISPLAY INVISIBLE (-2325 3400);
FORCEPROP 1 LAST OFFPAGE TRUE
J 2
(-2525 3375);
DISPLAY 0.872340 (-2525 3375);
PAINT GREEN (-2525 3375);
DISPLAY INVISIBLE (-2525 3375);
FORCEPROP 2 LAST CDS_LIB standard
J 0
(-2200 3500);
DISPLAY INVISIBLE (-2200 3500);
FORCEADD GND..1
(-3050 3000);
FORCEPROP 3 LASTPIN (-3050 3050) SIG_NAME GND\g
J 0
(-3040 3060);
DISPLAY 0.659574 (-3040 3060);
PAINT MONO (-3040 3060);
DISPLAY INVISIBLE (-3040 3060);
FORCEPROP 1 LAST SIZE 1B
J 0
(-2975 2950);
DISPLAY 0.851064 (-2975 2950);
PAINT GREEN (-2975 2950);
DISPLAY INVISIBLE (-2975 2950);
FORCEPROP 2 LAST BOM_COST MEM
J 0
(-3150 3075);
DISPLAY 0.808511 (-3150 3075);
DISPLAY INVISIBLE (-3150 3075);
FORCEPROP 2 LAST CDS_LIB pure_quanta_power
J 0
(-3050 3000);
DISPLAY INVISIBLE (-3050 3000);
FORCEPROP 1 LAST PATH I932
J 0
(-2975 3000);
DISPLAY 0.872340 (-2975 3000);
PAINT AQUA (-2975 3000);
DISPLAY INVISIBLE (-2975 3000);
FORCEPROP 1 LAST HDL_POWER GND
J 0
(-3050 3150);
DISPLAY 0.851064 (-3050 3150);
PAINT GREEN (-3050 3150);
DISPLAY INVISIBLE (-3050 3150);
FORCEADD Q_RES..2
(-3050 3225);
FORCEPROP 1 LAST LOCATION R25
J 0
(-3025 3350);
DISPLAY 0.489362 (-3025 3350);
PAINT SKYBLUE (-3025 3350);
FORCEPROP 0 LAST $SEC 1
J 0
(-3000 3400);
DISPLAY 0.680851 (-3000 3400);
PAINT MONO (-3000 3400);
DISPLAY INVISIBLE (-3000 3400);
FORCEPROP 0 LAST CDS_SEC 1
J 0
(-3000 3400);
DISPLAY 1.021277 (-3000 3400);
DISPLAY INVISIBLE (-3000 3400);
FORCEPROP 1 LASTPIN (-3050 3325) $PN 1
J 0
(-3045 3287);
DISPLAY 0.489362 (-3045 3287);
PAINT MONO (-3045 3287);
FORCEPROP 1 LASTPIN (-3050 3125) $PN 2
J 0
(-3045 3135);
DISPLAY 0.489362 (-3045 3135);
PAINT MONO (-3045 3135);
FORCEPROP 1 LAST WATTAGE 1/16W
J 0
(-3010 3200);
DISPLAY 0.489362 (-3010 3200);
PAINT SKYBLUE (-3010 3200);
FORCEPROP 1 LAST MATERIAL CHIP
J 0
(-3010 3150);
DISPLAY 0.489362 (-3010 3150);
PAINT SKYBLUE (-3010 3150);
FORCEPROP 1 LAST TOLERANCE 1%
J 0
(-3005 3250);
DISPLAY 0.489362 (-3005 3250);
PAINT SKYBLUE (-3005 3250);
FORCEPROP 1 LAST VALUE 10K
J 0
(-3005 3300);
DISPLAY 0.489362 (-3005 3300);
PAINT SKYBLUE (-3005 3300);
FORCEPROP 1 LAST PACK_TYPE 0402LF
J 0
(-3000 3100);
DISPLAY 0.489362 (-3000 3100);
PAINT SKYBLUE (-3000 3100);
FORCEPROP 2 LAST CDS_LIB pure_quanta
J 0
(-3050 3225);
DISPLAY INVISIBLE (-3050 3225);
FORCEPROP 2 LAST BOM_COST MEM
J 0
(-3000 3400);
DISPLAY 0.808511 (-3000 3400);
DISPLAY INVISIBLE (-3000 3400);
FORCEPROP 1 LAST PATH I933
J 0
(-3000 3400);
DISPLAY 0.978723 (-3000 3400);
PAINT WHITE (-3000 3400);
DISPLAY INVISIBLE (-3000 3400);
FORCEPROP 1 LAST PART_NUMBER CS31002FB08
J 0
(-3010 3100);
DISPLAY 0.489362 (-3010 3100);
PAINT SKYBLUE (-3010 3100);
DISPLAY INVISIBLE (-3010 3100);
FORCEPROP 2 LAST ROOM MEM_CH_A_CPU0_DIMM1
J 0
(-3000 3450);
DISPLAY 0.808511 (-3000 3450);
PAINT RED (-3000 3450);
DISPLAY INVISIBLE (-3000 3450);
FORCEADD Q_RES..2
(-3275 3225);
FORCEPROP 1 LAST LOCATION R12
J 0
(-3250 3350);
DISPLAY 0.489362 (-3250 3350);
PAINT SKYBLUE (-3250 3350);
FORCEPROP 0 LAST $SEC 1
J 0
(-3225 3400);
DISPLAY 0.680851 (-3225 3400);
PAINT MONO (-3225 3400);
DISPLAY INVISIBLE (-3225 3400);
FORCEPROP 0 LAST CDS_SEC 1
J 0
(-3225 3400);
DISPLAY 1.021277 (-3225 3400);
DISPLAY INVISIBLE (-3225 3400);
FORCEPROP 1 LASTPIN (-3275 3325) $PN 1
J 0
(-3270 3287);
DISPLAY 0.489362 (-3270 3287);
PAINT MONO (-3270 3287);
FORCEPROP 1 LASTPIN (-3275 3125) $PN 2
J 0
(-3270 3135);
DISPLAY 0.489362 (-3270 3135);
PAINT MONO (-3270 3135);
FORCEPROP 1 LAST WATTAGE 1/16W
J 0
(-3235 3200);
DISPLAY 0.489362 (-3235 3200);
PAINT SKYBLUE (-3235 3200);
FORCEPROP 1 LAST MATERIAL CHIP
J 0
(-3235 3150);
DISPLAY 0.489362 (-3235 3150);
PAINT SKYBLUE (-3235 3150);
FORCEPROP 1 LAST TOLERANCE 1%
J 0
(-3230 3250);
DISPLAY 0.489362 (-3230 3250);
PAINT SKYBLUE (-3230 3250);
FORCEPROP 1 LAST VALUE 10K
J 0
(-3230 3300);
DISPLAY 0.489362 (-3230 3300);
PAINT SKYBLUE (-3230 3300);
FORCEPROP 1 LAST PACK_TYPE 0402LF
J 0
(-3225 3100);
DISPLAY 0.489362 (-3225 3100);
PAINT SKYBLUE (-3225 3100);
FORCEPROP 2 LAST CDS_LIB pure_quanta
J 0
(-3275 3225);
DISPLAY INVISIBLE (-3275 3225);
FORCEPROP 2 LAST BOM_COST MEM
J 0
(-3225 3400);
DISPLAY 0.808511 (-3225 3400);
DISPLAY INVISIBLE (-3225 3400);
FORCEPROP 1 LAST PATH I934
J 0
(-3225 3400);
DISPLAY 0.978723 (-3225 3400);
PAINT WHITE (-3225 3400);
DISPLAY INVISIBLE (-3225 3400);
FORCEPROP 1 LAST PART_NUMBER CS31002FB08
J 0
(-3235 3100);
DISPLAY 0.489362 (-3235 3100);
PAINT SKYBLUE (-3235 3100);
DISPLAY INVISIBLE (-3235 3100);
FORCEPROP 2 LAST ROOM MEM_CH_A_CPU0_DIMM1
J 0
(-3225 3450);
DISPLAY 0.808511 (-3225 3450);
PAINT RED (-3225 3450);
DISPLAY INVISIBLE (-3225 3450);
FORCEADD GND..1
(-3275 3000);
FORCEPROP 3 LASTPIN (-3275 3050) SIG_NAME GND\g
J 0
(-3265 3060);
DISPLAY 0.659574 (-3265 3060);
PAINT MONO (-3265 3060);
DISPLAY INVISIBLE (-3265 3060);
FORCEPROP 1 LAST SIZE 1B
J 0
(-3200 2950);
DISPLAY 0.851064 (-3200 2950);
PAINT GREEN (-3200 2950);
DISPLAY INVISIBLE (-3200 2950);
FORCEPROP 2 LAST BOM_COST MEM
J 0
(-3375 3075);
DISPLAY 0.808511 (-3375 3075);
DISPLAY INVISIBLE (-3375 3075);
FORCEPROP 2 LAST CDS_LIB pure_quanta_power
J 0
(-3275 3000);
DISPLAY INVISIBLE (-3275 3000);
FORCEPROP 1 LAST PATH I935
J 0
(-3200 3000);
DISPLAY 0.872340 (-3200 3000);
PAINT AQUA (-3200 3000);
DISPLAY INVISIBLE (-3200 3000);
FORCEPROP 1 LAST HDL_POWER GND
J 0
(-3275 3150);
DISPLAY 0.851064 (-3275 3150);
PAINT GREEN (-3275 3150);
DISPLAY INVISIBLE (-3275 3150);
FORCEADD Q_RES..2
(-3475 3225);
FORCEPROP 1 LAST LOCATION R11
J 0
(-3450 3350);
DISPLAY 0.489362 (-3450 3350);
PAINT SKYBLUE (-3450 3350);
FORCEPROP 0 LAST $SEC 1
J 0
(-3425 3400);
DISPLAY 0.680851 (-3425 3400);
PAINT MONO (-3425 3400);
DISPLAY INVISIBLE (-3425 3400);
FORCEPROP 0 LAST CDS_SEC 1
J 0
(-3425 3400);
DISPLAY 1.021277 (-3425 3400);
DISPLAY INVISIBLE (-3425 3400);
FORCEPROP 1 LASTPIN (-3475 3325) $PN 1
J 0
(-3470 3287);
DISPLAY 0.489362 (-3470 3287);
PAINT MONO (-3470 3287);
FORCEPROP 1 LASTPIN (-3475 3125) $PN 2
J 0
(-3470 3135);
DISPLAY 0.489362 (-3470 3135);
PAINT MONO (-3470 3135);
FORCEPROP 1 LAST WATTAGE 1/16W
J 0
(-3435 3200);
DISPLAY 0.489362 (-3435 3200);
PAINT SKYBLUE (-3435 3200);
FORCEPROP 1 LAST MATERIAL CHIP
J 0
(-3435 3150);
DISPLAY 0.489362 (-3435 3150);
PAINT SKYBLUE (-3435 3150);
FORCEPROP 1 LAST TOLERANCE 1%
J 0
(-3430 3250);
DISPLAY 0.489362 (-3430 3250);
PAINT SKYBLUE (-3430 3250);
FORCEPROP 1 LAST VALUE 10K
J 0
(-3430 3300);
DISPLAY 0.489362 (-3430 3300);
PAINT SKYBLUE (-3430 3300);
FORCEPROP 1 LAST PACK_TYPE 0402LF
J 0
(-3425 3100);
DISPLAY 0.489362 (-3425 3100);
PAINT SKYBLUE (-3425 3100);
FORCEPROP 2 LAST CDS_LIB pure_quanta
J 0
(-3475 3225);
DISPLAY INVISIBLE (-3475 3225);
FORCEPROP 2 LAST BOM_COST MEM
J 0
(-3425 3400);
DISPLAY 0.808511 (-3425 3400);
DISPLAY INVISIBLE (-3425 3400);
FORCEPROP 1 LAST PATH I936
J 0
(-3425 3400);
DISPLAY 0.978723 (-3425 3400);
PAINT WHITE (-3425 3400);
DISPLAY INVISIBLE (-3425 3400);
FORCEPROP 1 LAST PART_NUMBER CS31002FB08
J 0
(-3435 3100);
DISPLAY 0.489362 (-3435 3100);
PAINT SKYBLUE (-3435 3100);
DISPLAY INVISIBLE (-3435 3100);
FORCEPROP 2 LAST ROOM MEM_CH_A_CPU0_DIMM1
J 0
(-3425 3450);
DISPLAY 0.808511 (-3425 3450);
PAINT RED (-3425 3450);
DISPLAY INVISIBLE (-3425 3450);
FORCEADD GND..1
(-3475 3000);
FORCEPROP 3 LASTPIN (-3475 3050) SIG_NAME GND\g
J 0
(-3465 3060);
DISPLAY 0.659574 (-3465 3060);
PAINT MONO (-3465 3060);
DISPLAY INVISIBLE (-3465 3060);
FORCEPROP 2 LAST BOM_COST MEM
J 0
(-3575 3075);
DISPLAY 0.808511 (-3575 3075);
DISPLAY INVISIBLE (-3575 3075);
FORCEPROP 1 LAST SIZE 1B
J 0
(-3400 2950);
DISPLAY 0.851064 (-3400 2950);
PAINT GREEN (-3400 2950);
DISPLAY INVISIBLE (-3400 2950);
FORCEPROP 2 LAST CDS_LIB pure_quanta_power
J 0
(-3475 3000);
DISPLAY INVISIBLE (-3475 3000);
FORCEPROP 1 LAST PATH I937
J 0
(-3400 3000);
DISPLAY 0.872340 (-3400 3000);
PAINT AQUA (-3400 3000);
DISPLAY INVISIBLE (-3400 3000);
FORCEPROP 1 LAST HDL_POWER GND
J 0
(-3475 3150);
DISPLAY 0.851064 (-3475 3150);
PAINT GREEN (-3475 3150);
DISPLAY INVISIBLE (-3475 3150);
FORCEADD GND..1
(-3675 3000);
FORCEPROP 3 LASTPIN (-3675 3050) SIG_NAME GND\g
J 0
(-3665 3060);
DISPLAY 0.659574 (-3665 3060);
PAINT MONO (-3665 3060);
DISPLAY INVISIBLE (-3665 3060);
FORCEPROP 1 LAST SIZE 1B
J 0
(-3600 2950);
DISPLAY 0.851064 (-3600 2950);
PAINT GREEN (-3600 2950);
DISPLAY INVISIBLE (-3600 2950);
FORCEPROP 2 LAST BOM_COST MEM
J 0
(-3775 3075);
DISPLAY 0.808511 (-3775 3075);
DISPLAY INVISIBLE (-3775 3075);
FORCEPROP 2 LAST CDS_LIB pure_quanta_power
J 0
(-3675 3000);
DISPLAY INVISIBLE (-3675 3000);
FORCEPROP 1 LAST PATH I938
J 0
(-3600 3000);
DISPLAY 0.872340 (-3600 3000);
PAINT AQUA (-3600 3000);
DISPLAY INVISIBLE (-3600 3000);
FORCEPROP 1 LAST HDL_POWER GND
J 0
(-3675 3150);
DISPLAY 0.851064 (-3675 3150);
PAINT GREEN (-3675 3150);
DISPLAY INVISIBLE (-3675 3150);
FORCEADD Q_RES..2
(-3675 3225);
FORCEPROP 1 LAST LOCATION R10
J 0
(-3650 3350);
DISPLAY 0.489362 (-3650 3350);
PAINT SKYBLUE (-3650 3350);
FORCEPROP 0 LAST $SEC 1
J 0
(-3625 3400);
DISPLAY 0.680851 (-3625 3400);
PAINT MONO (-3625 3400);
DISPLAY INVISIBLE (-3625 3400);
FORCEPROP 0 LAST CDS_SEC 1
J 0
(-3625 3400);
DISPLAY 1.021277 (-3625 3400);
DISPLAY INVISIBLE (-3625 3400);
FORCEPROP 1 LASTPIN (-3675 3325) $PN 1
J 0
(-3670 3287);
DISPLAY 0.489362 (-3670 3287);
PAINT MONO (-3670 3287);
FORCEPROP 1 LASTPIN (-3675 3125) $PN 2
J 0
(-3670 3135);
DISPLAY 0.489362 (-3670 3135);
PAINT MONO (-3670 3135);
FORCEPROP 1 LAST WATTAGE 1/16W
J 0
(-3635 3200);
DISPLAY 0.489362 (-3635 3200);
PAINT SKYBLUE (-3635 3200);
FORCEPROP 1 LAST MATERIAL CHIP
J 0
(-3635 3150);
DISPLAY 0.489362 (-3635 3150);
PAINT SKYBLUE (-3635 3150);
FORCEPROP 1 LAST TOLERANCE 1%
J 0
(-3630 3250);
DISPLAY 0.489362 (-3630 3250);
PAINT SKYBLUE (-3630 3250);
FORCEPROP 1 LAST VALUE 10K
J 0
(-3630 3300);
DISPLAY 0.489362 (-3630 3300);
PAINT SKYBLUE (-3630 3300);
FORCEPROP 1 LAST PACK_TYPE 0402LF
J 0
(-3625 3100);
DISPLAY 0.489362 (-3625 3100);
PAINT SKYBLUE (-3625 3100);
FORCEPROP 2 LAST CDS_LIB pure_quanta
J 0
(-3675 3225);
DISPLAY INVISIBLE (-3675 3225);
FORCEPROP 2 LAST BOM_COST MEM
J 0
(-3625 3400);
DISPLAY 0.808511 (-3625 3400);
DISPLAY INVISIBLE (-3625 3400);
FORCEPROP 1 LAST PATH I939
J 0
(-3625 3400);
DISPLAY 0.978723 (-3625 3400);
PAINT WHITE (-3625 3400);
DISPLAY INVISIBLE (-3625 3400);
FORCEPROP 1 LAST PART_NUMBER CS31002FB08
J 0
(-3635 3100);
DISPLAY 0.489362 (-3635 3100);
PAINT SKYBLUE (-3635 3100);
DISPLAY INVISIBLE (-3635 3100);
FORCEPROP 2 LAST ROOM MEM_CH_A_CPU0_DIMM1
J 0
(-3625 3450);
DISPLAY 0.808511 (-3625 3450);
PAINT RED (-3625 3450);
DISPLAY INVISIBLE (-3625 3450);
FORCEADD UNIVERSAL_POWER..1
R 2
(-6775 3300);
FORCEPROP 3 LASTPIN (-6775 3250) SIG_NAME P3V3_STBY\g
J 0
(-6765 3260);
DISPLAY 0.659574 (-6765 3260);
PAINT MONO (-6765 3260);
DISPLAY INVISIBLE (-6765 3260);
FORCEPROP 1 LAST HDL_POWER P3V3_STBY
J 1
(-6775 3350);
DISPLAY 0.489362 (-6775 3350);
PAINT GREEN (-6775 3350);
FORCEPROP 2 LAST CDS_LIB pure_quanta_power
J 2
(-6775 3300);
DISPLAY INVISIBLE (-6775 3300);
FORCEPROP 1 LAST PATH I940
J 2
(-6825 3325);
DISPLAY 0.872340 (-6825 3325);
PAINT AQUA (-6825 3325);
DISPLAY INVISIBLE (-6825 3325);
FORCEADD OFFPAGE..5
(-8200 3100);
FORCEPROP 2 LAST $XR0 79 
J 0
(-8454 3100);
DISPLAY 0.638298 (-8454 3100);
PAINT MONO (-8454 3100);
FORCEPROP 2 LAST PATH I941
J 0
(-8150 3175);
DISPLAY 0.680851 (-8150 3175);
DISPLAY INVISIBLE (-8150 3175);
FORCEPROP 1 LAST COMMENT_BODY TRUE
J 0
(-8100 3025);
DISPLAY 0.872340 (-8100 3025);
PAINT GREEN (-8100 3025);
DISPLAY INVISIBLE (-8100 3025);
FORCEPROP 1 LAST OFFPAGE TRUE
J 0
(-7875 2975);
DISPLAY 0.872340 (-7875 2975);
PAINT GREEN (-7875 2975);
DISPLAY INVISIBLE (-7875 2975);
FORCEPROP 2 LAST CDS_LIB standard
J 0
(-8200 3100);
DISPLAY INVISIBLE (-8200 3100);
FORCEADD OFFPAGE..5
(-8200 3050);
FORCEPROP 2 LAST $XR0 79 
J 0
(-8454 3050);
DISPLAY 0.638298 (-8454 3050);
PAINT MONO (-8454 3050);
FORCEPROP 2 LAST PATH I942
J 0
(-8150 3125);
DISPLAY 0.680851 (-8150 3125);
DISPLAY INVISIBLE (-8150 3125);
FORCEPROP 1 LAST COMMENT_BODY TRUE
J 0
(-8100 2975);
DISPLAY 0.872340 (-8100 2975);
PAINT GREEN (-8100 2975);
DISPLAY INVISIBLE (-8100 2975);
FORCEPROP 1 LAST OFFPAGE TRUE
J 0
(-7875 2925);
DISPLAY 0.872340 (-7875 2925);
PAINT GREEN (-7875 2925);
DISPLAY INVISIBLE (-7875 2925);
FORCEPROP 2 LAST CDS_LIB standard
J 0
(-8200 3050);
DISPLAY INVISIBLE (-8200 3050);
FORCEADD OFFPAGE..5
(-8200 2975);
FORCEPROP 2 LAST $XR1 79 
J 0
(-8575 2975);
DISPLAY 0.638298 (-8575 2975);
PAINT MONO (-8575 2975);
FORCEPROP 2 LAST $XR0 117 
J 0
(-8485 2975);
DISPLAY 0.638298 (-8485 2975);
PAINT MONO (-8485 2975);
FORCEPROP 2 LAST PATH I943
J 0
(-8150 3050);
DISPLAY 0.680851 (-8150 3050);
DISPLAY INVISIBLE (-8150 3050);
FORCEPROP 1 LAST COMMENT_BODY TRUE
J 0
(-8100 2900);
DISPLAY 0.872340 (-8100 2900);
PAINT GREEN (-8100 2900);
DISPLAY INVISIBLE (-8100 2900);
FORCEPROP 1 LAST OFFPAGE TRUE
J 0
(-7875 2850);
DISPLAY 0.872340 (-7875 2850);
PAINT GREEN (-7875 2850);
DISPLAY INVISIBLE (-7875 2850);
FORCEPROP 2 LAST CDS_LIB standard
J 0
(-8200 2975);
DISPLAY INVISIBLE (-8200 2975);
FORCEADD VCC_CORE..1
(-7050 2025);
FORCEPROP 3 LASTPIN (-7050 1975) SIG_NAME P1V8_STBY\g
J 0
(-7040 1985);
DISPLAY 0.659574 (-7040 1985);
PAINT MONO (-7040 1985);
DISPLAY INVISIBLE (-7040 1985);
FORCEPROP 1 LAST HDL_POWER P1V8_STBY
J 1
(-7050 2075);
DISPLAY 0.489362 (-7050 2075);
PAINT GREEN (-7050 2075);
FORCEPROP 2 LAST CDS_LIB pure_quanta_power
J 0
(-7050 2025);
DISPLAY INVISIBLE (-7050 2025);
FORCEPROP 1 LAST PATH I944
J 0
(-7000 2050);
DISPLAY 0.872340 (-7000 2050);
PAINT AQUA (-7000 2050);
DISPLAY INVISIBLE (-7000 2050);
FORCEADD Q_RES..2
(-7050 1700);
FORCEPROP 1 LAST LOCATION R1525
J 0
(-7005 1825);
DISPLAY 0.489362 (-7005 1825);
PAINT SKYBLUE (-7005 1825);
FORCEPROP 0 LAST $SEC 1
J 0
(-7000 1875);
DISPLAY 0.680851 (-7000 1875);
PAINT MONO (-7000 1875);
DISPLAY INVISIBLE (-7000 1875);
FORCEPROP 0 LAST CDS_SEC 1
J 0
(-7000 1875);
DISPLAY 0.680851 (-7000 1875);
DISPLAY INVISIBLE (-7000 1875);
FORCEPROP 1 LASTPIN (-7050 1800) $PN 1
J 0
(-7045 1762);
DISPLAY 0.489362 (-7045 1762);
PAINT MONO (-7045 1762);
FORCEPROP 1 LASTPIN (-7050 1600) $PN 2
J 0
(-7045 1610);
DISPLAY 0.489362 (-7045 1610);
PAINT MONO (-7045 1610);
FORCEPROP 1 LAST VALUE 4.7K
J 0
(-7005 1775);
DISPLAY 0.489362 (-7005 1775);
PAINT SKYBLUE (-7005 1775);
FORCEPROP 1 LAST MATERIAL EMPTY
J 0
(-7000 1700);
DISPLAY 0.489362 (-7000 1700);
PAINT RED (-7000 1700);
FORCEPROP 2 LAST CDS_LIB pure_quanta
J 0
(-7050 1700);
DISPLAY INVISIBLE (-7050 1700);
FORCEPROP 1 LAST PATH I945
J 0
(-7000 1875);
DISPLAY 0.978723 (-7000 1875);
PAINT WHITE (-7000 1875);
DISPLAY INVISIBLE (-7000 1875);
FORCEPROP 1 LAST WATTAGE 1/16W
J 0
(-7010 1675);
DISPLAY 0.978723 (-7010 1675);
PAINT SKYBLUE (-7010 1675);
DISPLAY INVISIBLE (-7010 1675);
FORCEPROP 1 LAST TOLERANCE 5%
J 0
(-7005 1725);
DISPLAY 0.978723 (-7005 1725);
PAINT SKYBLUE (-7005 1725);
DISPLAY INVISIBLE (-7005 1725);
FORCEPROP 1 LAST PART_NUMBER TMP_QCS24702JB38
J 0
(-7010 1575);
DISPLAY 0.978723 (-7010 1575);
PAINT SKYBLUE (-7010 1575);
DISPLAY INVISIBLE (-7010 1575);
FORCEPROP 1 LAST PACK_TYPE 0402LF
J 0
(-7025 1550);
DISPLAY 0.978723 (-7025 1550);
PAINT SKYBLUE (-7025 1550);
DISPLAY INVISIBLE (-7025 1550);
FORCEADD Q_RES..2
(-7300 1700);
FORCEPROP 1 LAST LOCATION R752
J 0
(-7255 1825);
DISPLAY 0.489362 (-7255 1825);
PAINT SKYBLUE (-7255 1825);
FORCEPROP 0 LAST $SEC 1
J 0
(-7250 1875);
DISPLAY 0.680851 (-7250 1875);
PAINT MONO (-7250 1875);
DISPLAY INVISIBLE (-7250 1875);
FORCEPROP 0 LAST CDS_SEC 1
J 0
(-7250 1875);
DISPLAY 0.680851 (-7250 1875);
DISPLAY INVISIBLE (-7250 1875);
FORCEPROP 1 LASTPIN (-7300 1800) $PN 1
J 0
(-7295 1762);
DISPLAY 0.489362 (-7295 1762);
PAINT MONO (-7295 1762);
FORCEPROP 1 LASTPIN (-7300 1600) $PN 2
J 0
(-7295 1610);
DISPLAY 0.489362 (-7295 1610);
PAINT MONO (-7295 1610);
FORCEPROP 1 LAST VALUE 4.7K
J 0
(-7255 1775);
DISPLAY 0.489362 (-7255 1775);
PAINT SKYBLUE (-7255 1775);
FORCEPROP 1 LAST PACK_TYPE 0402LF
J 0
(-7275 1550);
DISPLAY 0.978723 (-7275 1550);
PAINT SKYBLUE (-7275 1550);
DISPLAY INVISIBLE (-7275 1550);
FORCEPROP 1 LAST PART_NUMBER TMP_QCS24702JB38
J 0
(-7260 1575);
DISPLAY 0.978723 (-7260 1575);
PAINT SKYBLUE (-7260 1575);
DISPLAY INVISIBLE (-7260 1575);
FORCEPROP 1 LAST TOLERANCE 5%
J 0
(-7255 1725);
DISPLAY 0.978723 (-7255 1725);
PAINT SKYBLUE (-7255 1725);
DISPLAY INVISIBLE (-7255 1725);
FORCEPROP 1 LAST WATTAGE 1/16W
J 0
(-7260 1675);
DISPLAY 0.978723 (-7260 1675);
PAINT SKYBLUE (-7260 1675);
DISPLAY INVISIBLE (-7260 1675);
FORCEPROP 1 LAST PATH I946
J 0
(-7250 1875);
DISPLAY 0.978723 (-7250 1875);
PAINT WHITE (-7250 1875);
DISPLAY INVISIBLE (-7250 1875);
FORCEPROP 2 LAST CDS_LIB pure_quanta
J 0
(-7300 1700);
DISPLAY INVISIBLE (-7300 1700);
FORCEPROP 1 LAST MATERIAL CHIP
J 0
(-7250 1700);
DISPLAY 0.489362 (-7250 1700);
PAINT RED (-7250 1700);
DISPLAY INVISIBLE (-7250 1700);
FORCEADD Q_RES..2
(-7575 1700);
FORCEPROP 1 LAST LOCATION R741
J 0
(-7530 1825);
DISPLAY 0.489362 (-7530 1825);
PAINT SKYBLUE (-7530 1825);
FORCEPROP 0 LAST $SEC 1
J 0
(-7525 1875);
DISPLAY 0.680851 (-7525 1875);
PAINT MONO (-7525 1875);
DISPLAY INVISIBLE (-7525 1875);
FORCEPROP 0 LAST CDS_SEC 1
J 0
(-7525 1875);
DISPLAY 0.680851 (-7525 1875);
DISPLAY INVISIBLE (-7525 1875);
FORCEPROP 1 LASTPIN (-7575 1800) $PN 1
J 0
(-7570 1762);
DISPLAY 0.489362 (-7570 1762);
PAINT MONO (-7570 1762);
FORCEPROP 1 LASTPIN (-7575 1600) $PN 2
J 0
(-7570 1610);
DISPLAY 0.489362 (-7570 1610);
PAINT MONO (-7570 1610);
FORCEPROP 1 LAST VALUE 4.7K
J 0
(-7530 1775);
DISPLAY 0.489362 (-7530 1775);
PAINT SKYBLUE (-7530 1775);
FORCEPROP 1 LAST MATERIAL EMPTY
J 0
(-7525 1725);
DISPLAY 0.404255 (-7525 1725);
PAINT RED (-7525 1725);
FORCEPROP 1 LAST PACK_TYPE 0402LF
J 0
(-7550 1550);
DISPLAY 0.978723 (-7550 1550);
PAINT SKYBLUE (-7550 1550);
DISPLAY INVISIBLE (-7550 1550);
FORCEPROP 1 LAST PART_NUMBER TMP_QCS24702JB38
J 0
(-7535 1575);
DISPLAY 0.978723 (-7535 1575);
PAINT SKYBLUE (-7535 1575);
DISPLAY INVISIBLE (-7535 1575);
FORCEPROP 1 LAST TOLERANCE 5%
J 0
(-7530 1725);
DISPLAY 0.978723 (-7530 1725);
PAINT SKYBLUE (-7530 1725);
DISPLAY INVISIBLE (-7530 1725);
FORCEPROP 1 LAST WATTAGE 1/16W
J 0
(-7535 1675);
DISPLAY 0.978723 (-7535 1675);
PAINT SKYBLUE (-7535 1675);
DISPLAY INVISIBLE (-7535 1675);
FORCEPROP 1 LAST PATH I947
J 0
(-7525 1875);
DISPLAY 0.978723 (-7525 1875);
PAINT WHITE (-7525 1875);
DISPLAY INVISIBLE (-7525 1875);
FORCEPROP 2 LAST CDS_LIB pure_quanta
J 0
(-7575 1700);
DISPLAY INVISIBLE (-7575 1700);
FORCEADD Q_RES..2
(-7050 1200);
FORCEPROP 1 LAST LOCATION R1526
J 0
(-7005 1325);
DISPLAY 0.489362 (-7005 1325);
PAINT SKYBLUE (-7005 1325);
FORCEPROP 0 LAST $SEC 1
J 0
(-7000 1375);
DISPLAY 0.680851 (-7000 1375);
PAINT MONO (-7000 1375);
DISPLAY INVISIBLE (-7000 1375);
FORCEPROP 0 LAST CDS_SEC 1
J 0
(-7000 1375);
DISPLAY 0.680851 (-7000 1375);
DISPLAY INVISIBLE (-7000 1375);
FORCEPROP 1 LASTPIN (-7050 1300) $PN 1
J 0
(-7045 1262);
DISPLAY 0.489362 (-7045 1262);
PAINT MONO (-7045 1262);
FORCEPROP 1 LASTPIN (-7050 1100) $PN 2
J 0
(-7045 1110);
DISPLAY 0.489362 (-7045 1110);
PAINT MONO (-7045 1110);
FORCEPROP 1 LAST VALUE 4.7K
J 0
(-7005 1275);
DISPLAY 0.489362 (-7005 1275);
PAINT SKYBLUE (-7005 1275);
FORCEPROP 2 LAST CDS_LIB pure_quanta
J 0
(-7050 1200);
DISPLAY INVISIBLE (-7050 1200);
FORCEPROP 1 LAST PATH I948
J 0
(-7000 1375);
DISPLAY 0.978723 (-7000 1375);
PAINT WHITE (-7000 1375);
DISPLAY INVISIBLE (-7000 1375);
FORCEPROP 1 LAST WATTAGE 1/16W
J 0
(-7010 1175);
DISPLAY 0.978723 (-7010 1175);
PAINT SKYBLUE (-7010 1175);
DISPLAY INVISIBLE (-7010 1175);
FORCEPROP 1 LAST MATERIAL CHIP
J 0
(-7010 1125);
DISPLAY 0.978723 (-7010 1125);
PAINT SKYBLUE (-7010 1125);
DISPLAY INVISIBLE (-7010 1125);
FORCEPROP 1 LAST TOLERANCE 5%
J 0
(-7005 1225);
DISPLAY 0.978723 (-7005 1225);
PAINT SKYBLUE (-7005 1225);
DISPLAY INVISIBLE (-7005 1225);
FORCEPROP 1 LAST PART_NUMBER TMP_QCS24702JB38
J 0
(-7010 1075);
DISPLAY 0.978723 (-7010 1075);
PAINT SKYBLUE (-7010 1075);
DISPLAY INVISIBLE (-7010 1075);
FORCEPROP 1 LAST PACK_TYPE 0402LF
J 0
(-7025 1050);
DISPLAY 0.978723 (-7025 1050);
PAINT SKYBLUE (-7025 1050);
DISPLAY INVISIBLE (-7025 1050);
FORCEADD Q_RES..2
(-7300 1200);
FORCEPROP 1 LAST LOCATION R1524
J 0
(-7255 1325);
DISPLAY 0.489362 (-7255 1325);
PAINT SKYBLUE (-7255 1325);
FORCEPROP 0 LAST $SEC 1
J 0
(-7250 1375);
DISPLAY 0.680851 (-7250 1375);
PAINT MONO (-7250 1375);
DISPLAY INVISIBLE (-7250 1375);
FORCEPROP 0 LAST CDS_SEC 1
J 0
(-7250 1375);
DISPLAY 0.680851 (-7250 1375);
DISPLAY INVISIBLE (-7250 1375);
FORCEPROP 1 LASTPIN (-7300 1300) $PN 1
J 0
(-7295 1262);
DISPLAY 0.489362 (-7295 1262);
PAINT MONO (-7295 1262);
FORCEPROP 1 LASTPIN (-7300 1100) $PN 2
J 0
(-7295 1110);
DISPLAY 0.489362 (-7295 1110);
PAINT MONO (-7295 1110);
FORCEPROP 1 LAST MATERIAL EMPTY
J 0
(-7250 1225);
DISPLAY 0.404255 (-7250 1225);
PAINT RED (-7250 1225);
FORCEPROP 1 LAST VALUE 4.7K
J 0
(-7255 1275);
DISPLAY 0.489362 (-7255 1275);
PAINT SKYBLUE (-7255 1275);
FORCEPROP 1 LAST PACK_TYPE 0402LF
J 0
(-7275 1050);
DISPLAY 0.978723 (-7275 1050);
PAINT SKYBLUE (-7275 1050);
DISPLAY INVISIBLE (-7275 1050);
FORCEPROP 1 LAST PART_NUMBER TMP_QCS24702JB38
J 0
(-7260 1075);
DISPLAY 0.978723 (-7260 1075);
PAINT SKYBLUE (-7260 1075);
DISPLAY INVISIBLE (-7260 1075);
FORCEPROP 1 LAST TOLERANCE 5%
J 0
(-7255 1225);
DISPLAY 0.978723 (-7255 1225);
PAINT SKYBLUE (-7255 1225);
DISPLAY INVISIBLE (-7255 1225);
FORCEPROP 1 LAST WATTAGE 1/16W
J 0
(-7260 1175);
DISPLAY 0.978723 (-7260 1175);
PAINT SKYBLUE (-7260 1175);
DISPLAY INVISIBLE (-7260 1175);
FORCEPROP 1 LAST PATH I949
J 0
(-7250 1375);
DISPLAY 0.978723 (-7250 1375);
PAINT WHITE (-7250 1375);
DISPLAY INVISIBLE (-7250 1375);
FORCEPROP 2 LAST CDS_LIB pure_quanta
J 0
(-7300 1200);
DISPLAY INVISIBLE (-7300 1200);
FORCEADD Q_RES..2
(-7575 1200);
FORCEPROP 1 LAST LOCATION R749
J 0
(-7530 1325);
DISPLAY 0.489362 (-7530 1325);
PAINT SKYBLUE (-7530 1325);
FORCEPROP 0 LAST $SEC 1
J 0
(-7525 1375);
DISPLAY 0.680851 (-7525 1375);
PAINT MONO (-7525 1375);
DISPLAY INVISIBLE (-7525 1375);
FORCEPROP 0 LAST CDS_SEC 1
J 0
(-7525 1375);
DISPLAY 0.680851 (-7525 1375);
DISPLAY INVISIBLE (-7525 1375);
FORCEPROP 1 LASTPIN (-7575 1300) $PN 1
J 0
(-7570 1262);
DISPLAY 0.489362 (-7570 1262);
PAINT MONO (-7570 1262);
FORCEPROP 1 LASTPIN (-7575 1100) $PN 2
J 0
(-7570 1110);
DISPLAY 0.489362 (-7570 1110);
PAINT MONO (-7570 1110);
FORCEPROP 1 LAST VALUE 4.7K
J 0
(-7530 1275);
DISPLAY 0.489362 (-7530 1275);
PAINT SKYBLUE (-7530 1275);
FORCEPROP 1 LAST PACK_TYPE 0402LF
J 0
(-7550 1050);
DISPLAY 0.978723 (-7550 1050);
PAINT SKYBLUE (-7550 1050);
DISPLAY INVISIBLE (-7550 1050);
FORCEPROP 1 LAST PART_NUMBER TMP_QCS24702JB38
J 0
(-7535 1075);
DISPLAY 0.978723 (-7535 1075);
PAINT SKYBLUE (-7535 1075);
DISPLAY INVISIBLE (-7535 1075);
FORCEPROP 1 LAST TOLERANCE 5%
J 0
(-7530 1225);
DISPLAY 0.978723 (-7530 1225);
PAINT SKYBLUE (-7530 1225);
DISPLAY INVISIBLE (-7530 1225);
FORCEPROP 1 LAST WATTAGE 1/16W
J 0
(-7535 1175);
DISPLAY 0.978723 (-7535 1175);
PAINT SKYBLUE (-7535 1175);
DISPLAY INVISIBLE (-7535 1175);
FORCEPROP 1 LAST PATH I950
J 0
(-7525 1375);
DISPLAY 0.978723 (-7525 1375);
PAINT WHITE (-7525 1375);
DISPLAY INVISIBLE (-7525 1375);
FORCEPROP 2 LAST CDS_LIB pure_quanta
J 0
(-7575 1200);
DISPLAY INVISIBLE (-7575 1200);
FORCEPROP 1 LAST MATERIAL CHIP
J 0
(-7525 1200);
DISPLAY 0.489362 (-7525 1200);
PAINT RED (-7525 1200);
DISPLAY INVISIBLE (-7525 1200);
FORCEADD GND..1
(-7575 975);
FORCEPROP 3 LASTPIN (-7575 1025) SIG_NAME GND\g
J 0
(-7565 1035);
DISPLAY 0.659574 (-7565 1035);
PAINT MONO (-7565 1035);
DISPLAY INVISIBLE (-7565 1035);
FORCEPROP 2 LAST CDS_LIB pure_quanta_power
J 0
(-7575 975);
DISPLAY INVISIBLE (-7575 975);
FORCEPROP 1 LAST SIZE 1B
J 0
(-7500 925);
DISPLAY 0.851064 (-7500 925);
PAINT GREEN (-7500 925);
DISPLAY INVISIBLE (-7500 925);
FORCEPROP 2 LAST BOM_COST MEM
J 0
(-7675 1050);
DISPLAY 0.808511 (-7675 1050);
DISPLAY INVISIBLE (-7675 1050);
FORCEPROP 1 LAST PATH I951
J 0
(-7500 975);
DISPLAY 0.872340 (-7500 975);
PAINT AQUA (-7500 975);
DISPLAY INVISIBLE (-7500 975);
FORCEPROP 1 LAST HDL_POWER GND
J 0
(-7575 1125);
DISPLAY 0.851064 (-7575 1125);
PAINT GREEN (-7575 1125);
DISPLAY INVISIBLE (-7575 1125);
FORCEADD GND..1
(-7300 975);
FORCEPROP 3 LASTPIN (-7300 1025) SIG_NAME GND\g
J 0
(-7290 1035);
DISPLAY 0.659574 (-7290 1035);
PAINT MONO (-7290 1035);
DISPLAY INVISIBLE (-7290 1035);
FORCEPROP 2 LAST CDS_LIB pure_quanta_power
J 0
(-7300 975);
DISPLAY INVISIBLE (-7300 975);
FORCEPROP 2 LAST BOM_COST MEM
J 0
(-7400 1050);
DISPLAY 0.808511 (-7400 1050);
DISPLAY INVISIBLE (-7400 1050);
FORCEPROP 1 LAST SIZE 1B
J 0
(-7225 925);
DISPLAY 0.851064 (-7225 925);
PAINT GREEN (-7225 925);
DISPLAY INVISIBLE (-7225 925);
FORCEPROP 1 LAST PATH I952
J 0
(-7225 975);
DISPLAY 0.872340 (-7225 975);
PAINT AQUA (-7225 975);
DISPLAY INVISIBLE (-7225 975);
FORCEPROP 1 LAST HDL_POWER GND
J 0
(-7300 1125);
DISPLAY 0.851064 (-7300 1125);
PAINT GREEN (-7300 1125);
DISPLAY INVISIBLE (-7300 1125);
FORCEADD GND..1
(-7050 975);
FORCEPROP 3 LASTPIN (-7050 1025) SIG_NAME GND\g
J 0
(-7040 1035);
DISPLAY 0.659574 (-7040 1035);
PAINT MONO (-7040 1035);
DISPLAY INVISIBLE (-7040 1035);
FORCEPROP 2 LAST CDS_LIB pure_quanta_power
J 0
(-7050 975);
DISPLAY INVISIBLE (-7050 975);
FORCEPROP 2 LAST BOM_COST MEM
J 0
(-7150 1050);
DISPLAY 0.808511 (-7150 1050);
DISPLAY INVISIBLE (-7150 1050);
FORCEPROP 1 LAST SIZE 1B
J 0
(-6975 925);
DISPLAY 0.851064 (-6975 925);
PAINT GREEN (-6975 925);
DISPLAY INVISIBLE (-6975 925);
FORCEPROP 1 LAST PATH I953
J 0
(-6975 975);
DISPLAY 0.872340 (-6975 975);
PAINT AQUA (-6975 975);
DISPLAY INVISIBLE (-6975 975);
FORCEPROP 1 LAST HDL_POWER GND
J 0
(-7050 1125);
DISPLAY 0.851064 (-7050 1125);
PAINT GREEN (-7050 1125);
DISPLAY INVISIBLE (-7050 1125);
FORCEADD OFFPAGE..1
(-8350 1550);
FORCEPROP 2 LAST $XR0 81 
J 0
(-8601 1550);
DISPLAY 0.638298 (-8601 1550);
PAINT MONO (-8601 1550);
FORCEPROP 2 LAST PATH I954
J 0
(-8300 1625);
DISPLAY 0.680851 (-8300 1625);
DISPLAY INVISIBLE (-8300 1625);
FORCEPROP 1 LAST COMMENT_BODY TRUE
J 0
(-8225 1450);
DISPLAY 0.872340 (-8225 1450);
PAINT GREEN (-8225 1450);
DISPLAY INVISIBLE (-8225 1450);
FORCEPROP 1 LAST OFFPAGE TRUE
J 0
(-8025 1425);
DISPLAY 0.872340 (-8025 1425);
PAINT GREEN (-8025 1425);
DISPLAY INVISIBLE (-8025 1425);
FORCEPROP 2 LAST CDS_LIB standard
J 0
(-8350 1550);
DISPLAY INVISIBLE (-8350 1550);
FORCEADD OFFPAGE..1
(-8350 1500);
FORCEPROP 2 LAST $XR0 81 
J 0
(-8601 1500);
DISPLAY 0.638298 (-8601 1500);
PAINT MONO (-8601 1500);
FORCEPROP 2 LAST PATH I955
J 0
(-8300 1575);
DISPLAY 0.680851 (-8300 1575);
DISPLAY INVISIBLE (-8300 1575);
FORCEPROP 1 LAST COMMENT_BODY TRUE
J 0
(-8225 1400);
DISPLAY 0.872340 (-8225 1400);
PAINT GREEN (-8225 1400);
DISPLAY INVISIBLE (-8225 1400);
FORCEPROP 1 LAST OFFPAGE TRUE
J 0
(-8025 1375);
DISPLAY 0.872340 (-8025 1375);
PAINT GREEN (-8025 1375);
DISPLAY INVISIBLE (-8025 1375);
FORCEPROP 2 LAST CDS_LIB standard
J 0
(-8350 1500);
DISPLAY INVISIBLE (-8350 1500);
FORCEADD OFFPAGE..1
(-8350 1450);
FORCEPROP 2 LAST $XR0 81 
J 0
(-8601 1450);
DISPLAY 0.638298 (-8601 1450);
PAINT MONO (-8601 1450);
FORCEPROP 2 LAST PATH I956
J 0
(-8300 1525);
DISPLAY 0.680851 (-8300 1525);
DISPLAY INVISIBLE (-8300 1525);
FORCEPROP 1 LAST COMMENT_BODY TRUE
J 0
(-8225 1350);
DISPLAY 0.872340 (-8225 1350);
PAINT GREEN (-8225 1350);
DISPLAY INVISIBLE (-8225 1350);
FORCEPROP 1 LAST OFFPAGE TRUE
J 0
(-8025 1325);
DISPLAY 0.872340 (-8025 1325);
PAINT GREEN (-8025 1325);
DISPLAY INVISIBLE (-8025 1325);
FORCEPROP 2 LAST CDS_LIB standard
J 0
(-8350 1450);
DISPLAY INVISIBLE (-8350 1450);
FORCEADD Q_RES..1
(-7025 5225);
FORCEPROP 1 LAST LOCATION R1527
J 0
(-7325 5225);
DISPLAY 0.489362 (-7325 5225);
PAINT SKYBLUE (-7325 5225);
FORCEPROP 0 LAST $SEC 1
J 0
(-6900 5250);
DISPLAY 0.680851 (-6900 5250);
PAINT MONO (-6900 5250);
DISPLAY INVISIBLE (-6900 5250);
FORCEPROP 0 LAST CDS_SEC 1
J 0
(-6900 5250);
DISPLAY 0.680851 (-6900 5250);
DISPLAY INVISIBLE (-6900 5250);
FORCEPROP 1 LASTPIN (-7125 5225) $PN 1
J 0
(-7113 5237);
DISPLAY 0.489362 (-7113 5237);
PAINT MONO (-7113 5237);
FORCEPROP 1 LASTPIN (-6925 5225) $PN 2
J 0
(-6963 5237);
DISPLAY 0.489362 (-6963 5237);
PAINT MONO (-6963 5237);
FORCEPROP 1 LAST VALUE 4.7K
J 0
(-6900 5225);
DISPLAY 0.489362 (-6900 5225);
PAINT SKYBLUE (-6900 5225);
FORCEPROP 2 LAST CDS_LIB pure_quanta
J 0
(-7025 5225);
DISPLAY INVISIBLE (-7025 5225);
FORCEPROP 1 LAST PATH I957
J 0
(-7075 5375);
DISPLAY 0.978723 (-7075 5375);
PAINT WHITE (-7075 5375);
DISPLAY INVISIBLE (-7075 5375);
FORCEPROP 1 LAST WATTAGE 1/16W
J 2
(-7050 5075);
DISPLAY 0.510638 (-7050 5075);
PAINT SKYBLUE (-7050 5075);
DISPLAY INVISIBLE (-7050 5075);
FORCEPROP 1 LAST MATERIAL CHIP
J 0
(-6925 5200);
DISPLAY 0.489362 (-6925 5200);
PAINT SKYBLUE (-6925 5200);
DISPLAY INVISIBLE (-6925 5200);
FORCEPROP 1 LAST TOLERANCE 5%
J 0
(-6900 5225);
DISPLAY 0.510638 (-6900 5225);
PAINT SKYBLUE (-6900 5225);
DISPLAY INVISIBLE (-6900 5225);
FORCEPROP 1 LAST PART_NUMBER TMP_QCS24702JB38
J 0
(-7075 5325);
DISPLAY 0.510638 (-7075 5325);
PAINT SKYBLUE (-7075 5325);
DISPLAY INVISIBLE (-7075 5325);
FORCEPROP 1 LAST PACK_TYPE 0402LF
J 0
(-6775 5075);
DISPLAY 0.510638 (-6775 5075);
PAINT SKYBLUE (-6775 5075);
DISPLAY INVISIBLE (-6775 5075);
FORCEADD OFFPAGE..5
(-8175 5225);
FORCEPROP 2 LAST $XR1 80 
J 0
(-8550 5225);
DISPLAY 0.638298 (-8550 5225);
PAINT MONO (-8550 5225);
FORCEPROP 2 LAST $XR0 149 
J 0
(-8460 5225);
DISPLAY 0.638298 (-8460 5225);
PAINT MONO (-8460 5225);
FORCEPROP 2 LAST PATH I958
J 0
(-8125 5300);
DISPLAY 0.680851 (-8125 5300);
DISPLAY INVISIBLE (-8125 5300);
FORCEPROP 1 LAST COMMENT_BODY TRUE
J 0
(-8075 5150);
DISPLAY 0.872340 (-8075 5150);
PAINT GREEN (-8075 5150);
DISPLAY INVISIBLE (-8075 5150);
FORCEPROP 1 LAST OFFPAGE TRUE
J 0
(-7850 5100);
DISPLAY 0.872340 (-7850 5100);
PAINT GREEN (-7850 5100);
DISPLAY INVISIBLE (-7850 5100);
FORCEPROP 2 LAST CDS_LIB standard
J 0
(-8175 5225);
DISPLAY INVISIBLE (-8175 5225);
FORCEADD Q_RES..1
(-7025 4850);
FORCEPROP 1 LAST $LOCATION R1544
J 0
(-7325 4850);
DISPLAY 0.489362 (-7325 4850);
PAINT SKYBLUE (-7325 4850);
FORCEPROP 0 LAST CDS_LOCATION R1544
J 0
(-6900 4875);
DISPLAY 0.680851 (-6900 4875);
DISPLAY INVISIBLE (-6900 4875);
FORCEPROP 0 LAST $SEC 1
J 0
(-6900 4875);
DISPLAY 0.680851 (-6900 4875);
PAINT MONO (-6900 4875);
DISPLAY INVISIBLE (-6900 4875);
FORCEPROP 0 LAST CDS_SEC 1
J 0
(-6900 4875);
DISPLAY 0.680851 (-6900 4875);
DISPLAY INVISIBLE (-6900 4875);
FORCEPROP 1 LASTPIN (-7125 4850) $PN 1
J 0
(-7113 4862);
DISPLAY 0.787234 (-7113 4862);
PAINT MONO (-7113 4862);
FORCEPROP 1 LASTPIN (-6925 4850) $PN 2
J 0
(-6963 4862);
DISPLAY 0.787234 (-6963 4862);
PAINT MONO (-6963 4862);
FORCEPROP 1 LAST VALUE 4.7K
J 0
(-6900 4850);
DISPLAY 0.489362 (-6900 4850);
PAINT SKYBLUE (-6900 4850);
FORCEPROP 1 LAST PACK_TYPE 0402LF
J 0
(-6775 4700);
DISPLAY 0.510638 (-6775 4700);
PAINT SKYBLUE (-6775 4700);
DISPLAY INVISIBLE (-6775 4700);
FORCEPROP 1 LAST PART_NUMBER TMP_QCS24702JB38
J 0
(-7075 4950);
DISPLAY 0.510638 (-7075 4950);
PAINT SKYBLUE (-7075 4950);
DISPLAY INVISIBLE (-7075 4950);
FORCEPROP 1 LAST TOLERANCE 5%
J 0
(-6900 4850);
DISPLAY 0.510638 (-6900 4850);
PAINT SKYBLUE (-6900 4850);
DISPLAY INVISIBLE (-6900 4850);
FORCEPROP 1 LAST MATERIAL CHIP
J 0
(-6925 4825);
DISPLAY 0.489362 (-6925 4825);
PAINT SKYBLUE (-6925 4825);
DISPLAY INVISIBLE (-6925 4825);
FORCEPROP 1 LAST WATTAGE 1/16W
J 2
(-7050 4700);
DISPLAY 0.510638 (-7050 4700);
PAINT SKYBLUE (-7050 4700);
DISPLAY INVISIBLE (-7050 4700);
FORCEPROP 1 LAST PATH I959
J 0
(-7075 5000);
DISPLAY 0.978723 (-7075 5000);
PAINT WHITE (-7075 5000);
DISPLAY INVISIBLE (-7075 5000);
FORCEPROP 2 LAST CDS_LIB pure_quanta
J 0
(-7025 4850);
DISPLAY INVISIBLE (-7025 4850);
FORCEADD Q_RES..1
(-7025 4800);
FORCEPROP 1 LAST $LOCATION R1545
J 0
(-7325 4800);
DISPLAY 0.489362 (-7325 4800);
PAINT SKYBLUE (-7325 4800);
FORCEPROP 0 LAST CDS_LOCATION R1545
J 0
(-6900 4825);
DISPLAY 0.680851 (-6900 4825);
DISPLAY INVISIBLE (-6900 4825);
FORCEPROP 0 LAST $SEC 1
J 0
(-6900 4825);
DISPLAY 0.680851 (-6900 4825);
PAINT MONO (-6900 4825);
DISPLAY INVISIBLE (-6900 4825);
FORCEPROP 0 LAST CDS_SEC 1
J 0
(-6900 4825);
DISPLAY 0.680851 (-6900 4825);
DISPLAY INVISIBLE (-6900 4825);
FORCEPROP 1 LASTPIN (-7125 4800) $PN 1
J 0
(-7113 4812);
DISPLAY 0.787234 (-7113 4812);
PAINT MONO (-7113 4812);
FORCEPROP 1 LASTPIN (-6925 4800) $PN 2
J 0
(-6963 4812);
DISPLAY 0.787234 (-6963 4812);
PAINT MONO (-6963 4812);
FORCEPROP 1 LAST VALUE 4.7K
J 0
(-6900 4800);
DISPLAY 0.489362 (-6900 4800);
PAINT SKYBLUE (-6900 4800);
FORCEPROP 1 LAST PACK_TYPE 0402LF
J 0
(-6775 4650);
DISPLAY 0.510638 (-6775 4650);
PAINT SKYBLUE (-6775 4650);
DISPLAY INVISIBLE (-6775 4650);
FORCEPROP 1 LAST PART_NUMBER TMP_QCS24702JB38
J 0
(-7075 4900);
DISPLAY 0.510638 (-7075 4900);
PAINT SKYBLUE (-7075 4900);
DISPLAY INVISIBLE (-7075 4900);
FORCEPROP 1 LAST TOLERANCE 5%
J 0
(-6900 4800);
DISPLAY 0.510638 (-6900 4800);
PAINT SKYBLUE (-6900 4800);
DISPLAY INVISIBLE (-6900 4800);
FORCEPROP 1 LAST MATERIAL CHIP
J 0
(-6925 4775);
DISPLAY 0.489362 (-6925 4775);
PAINT SKYBLUE (-6925 4775);
DISPLAY INVISIBLE (-6925 4775);
FORCEPROP 1 LAST WATTAGE 1/16W
J 2
(-7050 4650);
DISPLAY 0.510638 (-7050 4650);
PAINT SKYBLUE (-7050 4650);
DISPLAY INVISIBLE (-7050 4650);
FORCEPROP 1 LAST PATH I961
J 0
(-7075 4950);
DISPLAY 0.978723 (-7075 4950);
PAINT WHITE (-7075 4950);
DISPLAY INVISIBLE (-7075 4950);
FORCEPROP 2 LAST CDS_LIB pure_quanta
J 0
(-7025 4800);
DISPLAY INVISIBLE (-7025 4800);
FORCEADD OFFPAGE..5
(-8175 4850);
FORCEPROP 2 LAST $XR1 80 
J 0
(-8550 4850);
DISPLAY 0.638298 (-8550 4850);
PAINT MONO (-8550 4850);
FORCEPROP 2 LAST $XR0 114 
J 0
(-8460 4850);
DISPLAY 0.638298 (-8460 4850);
PAINT MONO (-8460 4850);
FORCEPROP 1 LAST OFFPAGE TRUE
J 0
(-7850 4725);
DISPLAY 0.872340 (-7850 4725);
PAINT GREEN (-7850 4725);
DISPLAY INVISIBLE (-7850 4725);
FORCEPROP 1 LAST COMMENT_BODY TRUE
J 0
(-8075 4775);
DISPLAY 0.872340 (-8075 4775);
PAINT GREEN (-8075 4775);
DISPLAY INVISIBLE (-8075 4775);
FORCEPROP 2 LAST PATH I962
J 0
(-8125 4925);
DISPLAY 0.680851 (-8125 4925);
DISPLAY INVISIBLE (-8125 4925);
FORCEPROP 2 LAST CDS_LIB standard
J 0
(-8175 4850);
DISPLAY INVISIBLE (-8175 4850);
FORCEADD OFFPAGE..5
(-8175 4800);
FORCEPROP 2 LAST $XR1 80 
J 0
(-8550 4800);
DISPLAY 0.638298 (-8550 4800);
PAINT MONO (-8550 4800);
FORCEPROP 2 LAST $XR0 114 
J 0
(-8460 4800);
DISPLAY 0.638298 (-8460 4800);
PAINT MONO (-8460 4800);
FORCEPROP 1 LAST OFFPAGE TRUE
J 0
(-7850 4675);
DISPLAY 0.872340 (-7850 4675);
PAINT GREEN (-7850 4675);
DISPLAY INVISIBLE (-7850 4675);
FORCEPROP 1 LAST COMMENT_BODY TRUE
J 0
(-8075 4725);
DISPLAY 0.872340 (-8075 4725);
PAINT GREEN (-8075 4725);
DISPLAY INVISIBLE (-8075 4725);
FORCEPROP 2 LAST PATH I964
J 0
(-8125 4875);
DISPLAY 0.680851 (-8125 4875);
DISPLAY INVISIBLE (-8125 4875);
FORCEPROP 2 LAST CDS_LIB standard
J 0
(-8175 4800);
DISPLAY INVISIBLE (-8175 4800);
FORCEADD DNS..2
(-7025 1650);
PAINT RED (-7025 1650);
FORCEPROP 2 LAST CDS_LIB mstr_misc
J 0
(-7025 1650);
DISPLAY INVISIBLE (-7025 1650);
FORCEPROP 1 LAST COMMENT_BODY TRUE
R 1
J 0
(-6950 1425);
DISPLAY 0.872340 (-6950 1425);
PAINT PEACH (-6950 1425);
DISPLAY INVISIBLE (-6950 1425);
FORCEADD DNS..2
(-7550 1675);
PAINT RED (-7550 1675);
FORCEPROP 2 LAST CDS_LIB mstr_misc
J 0
(-7550 1675);
DISPLAY INVISIBLE (-7550 1675);
FORCEPROP 1 LAST COMMENT_BODY TRUE
R 1
J 0
(-7475 1450);
DISPLAY 0.872340 (-7475 1450);
PAINT PEACH (-7475 1450);
DISPLAY INVISIBLE (-7475 1450);
FORCEADD DNS..2
(-6925 3850);
PAINT RED (-6925 3850);
FORCEPROP 2 LAST CDS_LIB mstr_misc
J 0
(-6925 3850);
DISPLAY INVISIBLE (-6925 3850);
FORCEPROP 1 LAST COMMENT_BODY TRUE
R 1
J 0
(-6850 3625);
DISPLAY 0.872340 (-6850 3625);
PAINT PEACH (-6850 3625);
DISPLAY INVISIBLE (-6850 3625);
FORCEADD DNS..2
(-6950 4100);
PAINT RED (-6950 4100);
FORCEPROP 2 LAST CDS_LIB mstr_misc
J 0
(-6950 4100);
DISPLAY INVISIBLE (-6950 4100);
FORCEPROP 1 LAST COMMENT_BODY TRUE
R 1
J 0
(-6875 3875);
DISPLAY 0.872340 (-6875 3875);
PAINT PEACH (-6875 3875);
DISPLAY INVISIBLE (-6875 3875);
FORCEADD DNS..2
(-7275 1200);
PAINT RED (-7275 1200);
FORCEPROP 1 LAST COMMENT_BODY TRUE
R 1
J 0
(-7200 975);
DISPLAY 0.872340 (-7200 975);
PAINT PEACH (-7200 975);
DISPLAY INVISIBLE (-7200 975);
FORCEPROP 2 LAST CDS_LIB mstr_misc
J 0
(-7275 1200);
DISPLAY INVISIBLE (-7275 1200);
FORCEADD CAD_NOTE..1
(-3325 2375);
FORCEPROP 0 LAST L1 NEAR CPLD
J 0
(-3475 2250);
DISPLAY 0.617021 (-3475 2250);
PAINT WHITE (-3475 2250);
FORCEPROP 2 LAST CDS_LIB pure_quanta_power
J 0
(-3325 2375);
DISPLAY INVISIBLE (-3325 2375);
FORCEPROP 1 LAST COMMENT_BODY TRUE
J 0
(-3300 2475);
DISPLAY 0.574468 (-3300 2475);
PAINT WHITE (-3300 2475);
DISPLAY INVISIBLE (-3300 2475);
FORCEADD DNS..2
(-6925 3575);
PAINT RED (-6925 3575);
FORCEPROP 2 LAST CDS_LIB mstr_misc
J 0
(-6925 3575);
DISPLAY INVISIBLE (-6925 3575);
FORCEPROP 1 LAST COMMENT_BODY TRUE
R 1
J 0
(-6850 3350);
DISPLAY 0.872340 (-6850 3350);
PAINT PEACH (-6850 3350);
DISPLAY INVISIBLE (-6850 3350);
FORCEADD QUANTA_TITLE_BLOCK_C..1
(0 0);
FORCEPROP 0 LAST CDS_CON_LAST_MODIFIED Fri Mar 11 14:52:49 2022
J 0
(-1885 15);
DISPLAY INVISIBLE (-1885 15);
FORCEPROP 1 LAST CUSTOM_TXT_CDS <CON_LAST_MODIFIED>
J 0
(-1885 15);
DISPLAY 0.978723 (-1885 15);
FORCEPROP 2 LAST CUSTOM_TXT_CDS <XR_PAGE_TITLE>
J 0
(-7890 5250);
DISPLAY 0.638298 (-7890 5250);
PAINT PINK (-7890 5250);
DISPLAY INVISIBLE (-7890 5250);
FORCEPROP 1 LAST CUSTOM_TXT_CDS <NAME_2>
J 0
(-3175 50);
FORCEPROP 1 LAST CUSTOM_TXT_CDS <NAME_1>
J 0
(-3175 175);
FORCEPROP 1 LAST CUSTOM_TXT_CDS <Q_NUMBER>
J 0
(-1403 103);
DISPLAY 1.212766 (-1403 103);
FORCEPROP 1 LAST CUSTOM_TXT_CDS <Q_PROJ>
J 0
(-2382 102);
DISPLAY 1.212766 (-2382 102);
FORCEPROP 1 LAST CUSTOM_TXT_CDS <Q_REV>
J 0
(-184 103);
DISPLAY 1.212766 (-184 103);
FORCEPROP 1 LAST CUSTOM_TXT_CDS <CON_PAGE_NUM> OF <CON_TOTAL_PAGES>
J 0
(-446 18);
DISPLAY 0.978723 (-446 18);
FORCEPROP 1 LAST Q_TITLE FPGA 4/6
J 0
(-9300 50);
DISPLAY 2.446809 (-9300 50);
PAINT GREEN (-9300 50);
FORCEPROP 1 LAST Q_DEPT BU9
J 1
(-3763 49);
DISPLAY 1.957447 (-3763 49);
PAINT GREEN (-3763 49);
FORCEPROP 2 LAST CDS_LIB pure_quanta
J 0
(0 0);
DISPLAY INVISIBLE (0 0);
FORCEPROP 1 LAST CDS_LMAN_SYM_OUTLINE -9475,6775,100,-125
J 0
(0 0);
DISPLAY 0.468085 (0 0);
PAINT GREEN (0 0);
DISPLAY INVISIBLE (0 0);
FORCEPROP 2 LAST PAGE_BORDER TRUE
J 0
(-7890 5250);
DISPLAY 0.638298 (-7890 5250);
PAINT PINK (-7890 5250);
DISPLAY INVISIBLE (-7890 5250);
FORCEPROP 1 LAST COMMENT_BODY TRUE
J 0
(12 -13);
DISPLAY 0.978723 (12 -13);
PAINT GREEN (12 -13);
DISPLAY INVISIBLE (12 -13);
FORCEPROP 2 LAST CDS_XR_PAGE_TITLE CR-82 : @T6G_MB_LIB.T6G(SCH_1):PAGE82
J 0
(-7890 5250);
DISPLAY 0.638298 (-7890 5250);
PAINT PINK (-7890 5250);
DISPLAY INVISIBLE (-7890 5250);
FORCEADD CAD_NOTE..1
(-1000 2350);
FORCEPROP 0 LAST L1 NEAR CPLD
J 0
(-1150 2225);
DISPLAY 0.617021 (-1150 2225);
PAINT WHITE (-1150 2225);
FORCEPROP 2 LAST CDS_LIB pure_quanta_power
J 0
(-1000 2350);
DISPLAY INVISIBLE (-1000 2350);
FORCEPROP 1 LAST COMMENT_BODY TRUE
J 0
(-975 2450);
DISPLAY 0.574468 (-975 2450);
PAINT WHITE (-975 2450);
DISPLAY INVISIBLE (-975 2450);
WIRE 16 -1 (-3600 4275)(-3600 4350);
WIRE 16 -1 (-2850 5600)(-2850 5675);
WIRE 16 -1 (-2325 4275)(-2325 4350);
WIRE 16 -1 (-2450 4275)(-2450 4350);
WIRE 16 -1 (-2575 4275)(-2575 4350);
WIRE 16 -1 (-2700 4275)(-2700 4350);
WIRE 16 -1 (-2825 4275)(-2825 4350);
WIRE 16 -1 (-2975 4275)(-2975 4350);
WIRE 16 -1 (-3075 5600)(-3075 5675);
WIRE 16 -1 (-3275 5600)(-3275 5675);
WIRE 16 -1 (-3475 5600)(-3475 5675);
WIRE 16 -1 (-3100 4275)(-3100 4350);
WIRE 16 -1 (-3225 4275)(-3225 4350);
WIRE 16 -1 (-3475 4275)(-3475 4350);
WIRE 16 -1 (-3350 4275)(-3350 4350);
WIRE 16 -1 (-3050 3050)(-3050 3125);
WIRE 16 -1 (-3275 3050)(-3275 3125);
WIRE 16 -1 (-3475 3050)(-3475 3125);
WIRE 16 -1 (-3675 3050)(-3675 3125);
WIRE 16 -1 (-7575 1025)(-7575 1100);
WIRE 16 -1 (-7300 1025)(-7300 1100);
WIRE 16 -1 (-7050 1025)(-7050 1100);
WIRE 16 -1 (-7300 1600)(-7300 1500);
WIRE 16 -1 (-7300 1500)(-7300 1300);
WIRE 16 -1 (-7300 1500)(-8300 1500);
FORCEPROP 2 LAST SIG_NAME HPM_BRD_REV_ID1
J 0
(-8285 1510);
DISPLAY 0.489362 (-8285 1510);
WIRE 16 -1 (-7050 1600)(-7050 1450);
WIRE 16 -1 (-7050 1450)(-7050 1300);
WIRE 16 -1 (-7050 1450)(-8300 1450);
FORCEPROP 2 LAST SIG_NAME HPM_BRD_REV_ID2
J 0
(-8285 1460);
DISPLAY 0.489362 (-8285 1460);
WIRE 16 -1 (-6100 2000)(-6100 950);
WIRE 16 -1 (-5725 2000)(-6100 2000);
WIRE 16 -1 (-6100 2000)(-6450 2000);
WIRE 16 -1 (-5725 950)(-6100 950);
WIRE 16 -1 (-6100 950)(-6450 950);
WIRE 16 -1 (-6450 950)(-6450 1225);
WIRE 16 -1 (-5725 2000)(-5725 950);
WIRE 16 -1 (-5375 950)(-5725 950);
WIRE 16 -1 (-6450 1825)(-6450 2000);
WIRE 16 -1 (-5375 2000)(-5725 2000);
WIRE 16 -1 (-5375 2000)(-5375 950);
WIRE 16 -1 (-5075 2000)(-5375 2000);
WIRE 16 -1 (-6450 1825)(-5075 1825);
WIRE 16 -1 (-6450 1825)(-6450 1625);
WIRE 16 -1 (-5075 950)(-5375 950);
WIRE 16 -1 (-6450 1225)(-5075 1225);
WIRE 16 -1 (-6450 1425)(-6450 1225);
WIRE 16 -1 (-6450 1425)(-5075 1425);
WIRE 16 -1 (-6450 1625)(-6450 1425);
WIRE 16 -1 (-5075 1225)(-5075 950);
WIRE 16 -1 (-5075 1425)(-5075 1225);
WIRE 16 -1 (-6450 1625)(-5075 1625);
WIRE 16 -1 (-5075 2000)(-5075 1825);
WIRE 16 -1 (-5075 1825)(-5075 1625);
WIRE 16 -1 (-5075 1625)(-5075 1425);
WIRE 16 -1 (-7575 1600)(-7575 1550);
WIRE 16 -1 (-7575 1550)(-7575 1300);
WIRE 16 -1 (-7575 1550)(-8300 1550);
FORCEPROP 2 LAST SIG_NAME HPM_BRD_REV_ID0
J 0
(-8285 1560);
DISPLAY 0.489362 (-8285 1560);
WIRE 16 -1 (-7050 1975)(-7050 1950);
WIRE 16 -1 (-7050 1950)(-7050 1800);
WIRE 16 -1 (-7300 1950)(-7050 1950);
WIRE 16 -1 (-7300 1800)(-7300 1950);
WIRE 16 -1 (-7575 1950)(-7300 1950);
WIRE 16 -1 (-7575 1800)(-7575 1950);
WIRE 16 -1 (-8125 4850)(-7125 4850);
FORCEPROP 2 LAST SIG_NAME PRSNT1_SLOT1_N
J 0
(-8035 4860);
DISPLAY 0.446809 (-8035 4860);
WIRE 16 -1 (-7125 4800)(-8125 4800);
FORCEPROP 2 LAST SIG_NAME PRSNT2_SLOT1_N
J 0
(-8035 4810);
DISPLAY 0.446809 (-8035 4810);
WIRE 16 -1 (-8125 4725)(-7125 4725);
FORCEPROP 2 LAST SIG_NAME PRSNT1_SLOT2_N
J 0
(-8025 4735);
DISPLAY 0.489362 (-8025 4735);
WIRE 16 -1 (-8125 4675)(-7125 4675);
FORCEPROP 2 LAST SIG_NAME PRSNT2_SLOT2_N
J 0
(-8025 4685);
DISPLAY 0.489362 (-8025 4685);
WIRE 16 -1 (-7125 4625)(-8125 4625);
FORCEPROP 2 LAST SIG_NAME PRSNT_SLOT3_N
J 0
(-8025 4635);
DISPLAY 0.489362 (-8025 4635);
WIRE 16 -1 (-8125 4550)(-7125 4550);
FORCEPROP 0 LAST SIG_NAME PRSNT_N_E1S_1_R
J 0
(-8025 4560);
DISPLAY 0.489362 (-8025 4560);
WIRE 16 -1 (-8125 4500)(-7125 4500);
FORCEPROP 0 LAST SIG_NAME PRSNT_N_E1S_2_R
J 0
(-8025 4510);
DISPLAY 0.489362 (-8025 4510);
WIRE 16 -1 (-8125 4450)(-7125 4450);
FORCEPROP 0 LAST SIG_NAME PRSNT_N_E1S_3_R
J 0
(-8025 4460);
DISPLAY 0.489362 (-8025 4460);
WIRE 16 -1 (-7125 4975)(-8125 4975);
FORCEPROP 2 LAST SIG_NAME RST_SMBMUX_U8_N
J 0
(-8025 4985);
DISPLAY 0.489362 (-8025 4985);
WIRE 16 -1 (-7125 5025)(-8125 5025);
FORCEPROP 2 LAST SIG_NAME RST_SMBMUX_U7_N
J 0
(-8025 5035);
DISPLAY 0.489362 (-8025 5035);
WIRE 16 -1 (-6775 3575)(-6775 3625);
WIRE 16 -1 (-6775 3575)(-6925 3575);
WIRE 16 -1 (-6775 3775)(-6775 3625);
WIRE 16 -1 (-6775 3625)(-6925 3625);
WIRE 16 -1 (-6775 3825)(-6775 3775);
WIRE 16 -1 (-6775 3775)(-6925 3775);
WIRE 16 -1 (-6775 3875)(-6775 3825);
WIRE 16 -1 (-6775 3825)(-6925 3825);
WIRE 16 -1 (-6775 3925)(-6775 3875);
WIRE 16 -1 (-6775 3875)(-6925 3875);
WIRE 16 -1 (-6775 3925)(-6775 4025);
WIRE 16 -1 (-6775 3925)(-6925 3925);
WIRE 16 -1 (-6775 4075)(-6775 4025);
WIRE 16 -1 (-6775 4025)(-6925 4025);
WIRE 16 -1 (-6925 4075)(-6775 4075);
WIRE 16 -1 (-6775 4125)(-6775 4075);
WIRE 16 -1 (-6775 4175)(-6775 4125);
WIRE 16 -1 (-6925 4125)(-6775 4125);
WIRE 16 -1 (-6925 4175)(-6775 4175);
WIRE 16 -1 (-6775 4300)(-6775 4175);
WIRE 16 -1 (-6775 4400)(-6775 4300);
WIRE 16 -1 (-6775 4300)(-6925 4300);
WIRE 16 -1 (-6775 4450)(-6775 4400);
WIRE 16 -1 (-6775 4400)(-6925 4400);
WIRE 16 -1 (-6775 4500)(-6775 4450);
WIRE 16 -1 (-6775 4450)(-6925 4450);
WIRE 16 -1 (-6775 4550)(-6775 4500);
WIRE 16 -1 (-6775 4500)(-6925 4500);
WIRE 16 -1 (-6775 4625)(-6775 4550);
WIRE 16 -1 (-6775 4550)(-6925 4550);
WIRE 16 -1 (-6775 4675)(-6775 4625);
WIRE 16 -1 (-6775 4625)(-6925 4625);
WIRE 16 -1 (-6775 4725)(-6775 4675);
WIRE 16 -1 (-6775 4675)(-6925 4675);
WIRE 16 -1 (-6925 4725)(-6775 4725);
WIRE 16 -1 (-6775 4725)(-6775 4800);
WIRE 16 -1 (-6775 4800)(-6775 4850);
WIRE 16 -1 (-6775 4800)(-6925 4800);
WIRE 16 -1 (-6775 4975)(-6775 4850);
WIRE 16 -1 (-6775 4850)(-6925 4850);
WIRE 16 -1 (-6925 4975)(-6775 4975);
WIRE 16 -1 (-6775 5025)(-6775 4975);
WIRE 16 -1 (-6925 5025)(-6775 5025);
WIRE 16 -1 (-6775 5025)(-6775 5100);
WIRE 16 -1 (-6775 5225)(-6775 5100);
WIRE 16 -1 (-6775 5100)(-6925 5100);
WIRE 16 -1 (-6775 5300)(-6775 5225);
WIRE 16 -1 (-6925 5225)(-6775 5225);
WIRE 16 -1 (-6775 5300)(-6775 5350);
WIRE 16 -1 (-6775 5300)(-6925 5300);
WIRE 16 -1 (-6775 5400)(-6775 5350);
WIRE 16 -1 (-6775 5350)(-6925 5350);
WIRE 16 -1 (-6775 5400)(-6775 5450);
WIRE 16 -1 (-6775 5400)(-6925 5400);
WIRE 16 -1 (-6775 5500)(-6775 5450);
WIRE 16 -1 (-6775 5450)(-6925 5450);
WIRE 16 -1 (-6775 5550)(-6775 5500);
WIRE 16 -1 (-6775 5500)(-6925 5500);
WIRE 16 -1 (-6775 5575)(-6775 5550);
WIRE 16 -1 (-6775 5550)(-6925 5550);
WIRE 16 -1 (-8125 5500)(-7125 5500);
FORCEPROP 2 LAST SIG_NAME PVDDCR_CPU1_P0_SMB_ALERT
J 0
(-8025 5510);
DISPLAY 0.489362 (-8025 5510);
WIRE 16 -1 (-7125 5450)(-8125 5450);
FORCEPROP 2 LAST SIG_NAME PVDDCR_CPU0_P1_PMALERT
J 0
(-8025 5460);
DISPLAY 0.489362 (-8025 5460);
WIRE 16 -1 (-8125 5100)(-7125 5100);
FORCEPROP 2 LAST SIG_NAME RM_THROTTLE_N
J 0
(-8025 5110);
DISPLAY 0.489362 (-8025 5110);
WIRE 16 -1 (-8125 5225)(-7125 5225);
FORCEPROP 2 LAST SIG_NAME PRSNT_HDT_N
J 0
(-8025 5235);
DISPLAY 0.489362 (-8025 5235);
WIRE 16 -1 (-7125 5300)(-8125 5300);
FORCEPROP 2 LAST SIG_NAME PVDD11_S3_P1_PMALERT
J 0
(-8025 5310);
DISPLAY 0.489362 (-8025 5310);
WIRE 16 -1 (-8125 5400)(-7125 5400);
FORCEPROP 2 LAST SIG_NAME PVDDCR_CPU1_P1_SMB_ALERT
J 0
(-8025 5410);
DISPLAY 0.489362 (-8025 5410);
WIRE 16 -1 (-7125 5350)(-8125 5350);
FORCEPROP 2 LAST SIG_NAME PVDD11_S3_P0_PMALERT
J 0
(-8025 5360);
DISPLAY 0.489362 (-8025 5360);
WIRE 16 -1 (-7125 5550)(-8125 5550);
FORCEPROP 2 LAST SIG_NAME PVDDCR_CPU0_P0_PMALERT
J 0
(-8025 5560);
DISPLAY 0.489362 (-8025 5560);
WIRE 16 -1 (-3800 1050)(-3525 1050);
WIRE 16 -1 (-3800 1150)(-3800 1050);
WIRE 16 -1 (-3800 1150)(-3525 1150);
WIRE 16 -1 (-3800 1250)(-3800 1150);
WIRE 16 -1 (-3800 1250)(-3525 1250);
WIRE 16 -1 (-3800 1350)(-3800 1250);
WIRE 16 -1 (-3800 1350)(-3525 1350);
WIRE 16 -1 (-3800 1550)(-3800 1350);
WIRE 16 -1 (-3800 1550)(-3525 1550);
WIRE 16 -1 (-3800 1650)(-3800 1550);
WIRE 16 -1 (-3800 1650)(-3525 1650);
WIRE 16 -1 (-3800 1750)(-3800 1650);
WIRE 16 -1 (-3800 1750)(-3525 1750);
WIRE 16 -1 (-3800 1850)(-3800 1750);
WIRE 16 -1 (-3800 1850)(-3525 1850);
WIRE 16 -1 (-3800 1950)(-3800 1850);
WIRE 16 -1 (-3800 2075)(-3800 1950);
WIRE 16 -1 (-3800 1950)(-3525 1950);
WIRE 16 -1 (-6800 5775)(-6800 5725);
WIRE 16 -1 (-6800 5825)(-6800 5775);
WIRE 16 -1 (-6800 5775)(-6925 5775);
WIRE 16 -1 (-6800 5725)(-6925 5725);
WIRE 16 -1 (-6800 5875)(-6800 5825);
WIRE 16 -1 (-6800 5825)(-6925 5825);
WIRE 16 -1 (-6925 5875)(-6800 5875);
WIRE 16 -1 (-6800 5925)(-6800 5875);
WIRE 16 -1 (-6925 5925)(-6800 5925);
WIRE 16 -1 (-6800 5975)(-6800 5925);
WIRE 16 -1 (-6925 5975)(-6800 5975);
WIRE 16 -1 (-6800 6025)(-6800 5975);
WIRE 16 -1 (-6925 6025)(-6800 6025);
WIRE 16 -1 (-6800 6075)(-6800 6025);
WIRE 16 -1 (-6925 6075)(-6800 6075);
WIRE 16 -1 (-6800 6125)(-6800 6075);
WIRE 16 -1 (-6800 6300)(-6800 6125);
WIRE 16 -1 (-6925 6125)(-6800 6125);
WIRE 16 -1 (-8125 4400)(-7125 4400);
FORCEPROP 0 LAST SIG_NAME PRSNT_N_E1S_4_R
J 0
(-8025 4410);
DISPLAY 0.489362 (-8025 4410);
WIRE 16 -1 (-7150 2975)(-8150 2975);
FORCEPROP 2 LAST SIG_NAME SCM_SYS_PWRBTN_N
J 0
(-8025 2985);
DISPLAY 0.489362 (-8025 2985);
WIRE 16 -1 (-8150 4025)(-7125 4025);
FORCEPROP 2 LAST SIG_NAME P12V_E1S_4_EN_R
J 0
(-8025 4035);
DISPLAY 0.489362 (-8025 4035);
WIRE 16 -1 (-8150 4075)(-7125 4075);
FORCEPROP 2 LAST SIG_NAME P12V_E1S_3_EN_R
J 0
(-8025 4085);
DISPLAY 0.489362 (-8025 4085);
WIRE 16 -1 (-8150 4125)(-7125 4125);
FORCEPROP 2 LAST SIG_NAME P12V_E1S_2_EN_R
J 0
(-8025 4135);
DISPLAY 0.489362 (-8025 4135);
WIRE 16 -1 (-8150 4175)(-7125 4175);
FORCEPROP 2 LAST SIG_NAME P12V_E1S_1_EN_R
J 0
(-8025 4185);
DISPLAY 0.489362 (-8025 4185);
WIRE 16 -1 (-8150 4300)(-7125 4300);
FORCEPROP 0 LAST CDS_PHYS_NET_NAME FM_SYS_THROTTLE_N
J 0
(-8125 4342);
PAINT MONO (-8125 4342);
DISPLAY INVISIBLE (-8125 4342);
FORCEPROP 0 LAST SIG_NAME FM_SYS_THROTTLE_N
J 0
(-8025 4310);
DISPLAY 0.489362 (-8025 4310);
WIRE 16 -1 (-1550 500)(-1275 500);
WIRE 16 -1 (-1550 600)(-1550 500);
WIRE 16 -1 (-1550 600)(-1275 600);
WIRE 16 -1 (-1550 700)(-1550 600);
WIRE 16 -1 (-1550 700)(-1275 700);
WIRE 16 -1 (-1550 800)(-1550 700);
WIRE 16 -1 (-1550 800)(-1275 800);
WIRE 16 -1 (-1550 900)(-1550 800);
WIRE 16 -1 (-1550 900)(-1275 900);
WIRE 16 -1 (-1550 1000)(-1550 900);
WIRE 16 -1 (-1550 1100)(-1550 1000);
WIRE 16 -1 (-1550 1000)(-1275 1000);
WIRE 16 -1 (-1550 1100)(-1275 1100);
WIRE 16 -1 (-1550 1200)(-1550 1100);
WIRE 16 -1 (-1550 1200)(-1275 1200);
WIRE 16 -1 (-1550 1300)(-1550 1200);
WIRE 16 -1 (-1550 1300)(-1275 1300);
WIRE 16 -1 (-1550 1400)(-1550 1300);
WIRE 16 -1 (-1550 1400)(-1275 1400);
WIRE 16 -1 (-1550 1500)(-1550 1400);
WIRE 16 -1 (-1550 1500)(-1275 1500);
WIRE 16 -1 (-1550 1600)(-1550 1500);
WIRE 16 -1 (-1550 1600)(-1275 1600);
WIRE 16 -1 (-1550 1700)(-1550 1600);
WIRE 16 -1 (-1550 1700)(-1275 1700);
WIRE 16 -1 (-1550 1800)(-1550 1700);
WIRE 16 -1 (-1550 2075)(-1550 1800);
WIRE 16 -1 (-1550 1800)(-1275 1800);
WIRE 16 -1 (-1075 1800)(-350 1800);
WIRE 16 -1 (-350 1800)(-350 1700);
WIRE 16 -1 (-1075 1700)(-350 1700);
WIRE 16 -1 (-350 1700)(-350 1600);
WIRE 16 -1 (-1075 1600)(-350 1600);
WIRE 16 -1 (-350 1500)(-350 1600);
WIRE 16 -1 (-1075 1500)(-350 1500);
WIRE 16 -1 (-350 1400)(-350 1500);
WIRE 16 -1 (-1075 1400)(-350 1400);
WIRE 16 -1 (-350 1300)(-350 1400);
WIRE 16 -1 (-1075 1300)(-350 1300);
WIRE 16 -1 (-350 1200)(-350 1300);
WIRE 16 -1 (-1075 1200)(-350 1200);
WIRE 16 -1 (-350 1100)(-350 1200);
WIRE 16 -1 (-1075 1100)(-350 1100);
WIRE 16 -1 (-350 1000)(-350 1100);
WIRE 16 -1 (-1075 1000)(-350 1000);
WIRE 16 -1 (-350 1000)(-350 900);
WIRE 16 -1 (-1075 900)(-350 900);
WIRE 16 -1 (-350 800)(-350 900);
WIRE 16 -1 (-1075 800)(-350 800);
WIRE 16 -1 (-350 800)(-350 700);
WIRE 16 -1 (-1075 700)(-350 700);
WIRE 16 -1 (-350 600)(-350 700);
WIRE 16 -1 (-350 500)(-350 600);
WIRE 16 -1 (-1075 600)(-350 600);
WIRE 16 -1 (-1075 500)(-350 500);
WIRE 16 -1 (-3325 1950)(-2075 1950);
WIRE 16 -1 (-2075 1950)(-2075 1850);
WIRE 16 -1 (-3325 1850)(-2075 1850);
WIRE 16 -1 (-2075 1850)(-2075 1750);
WIRE 16 -1 (-3325 1750)(-2075 1750);
WIRE 16 -1 (-2075 1750)(-2075 1650);
WIRE 16 -1 (-3325 1650)(-2075 1650);
WIRE 16 -1 (-2075 1650)(-2075 1550);
WIRE 16 -1 (-3325 1550)(-2075 1550);
WIRE 16 -1 (-2075 1350)(-2075 1550);
WIRE 16 -1 (-3325 1350)(-2075 1350);
WIRE 16 -1 (-2075 1250)(-2075 1350);
WIRE 16 -1 (-3325 1250)(-2075 1250);
WIRE 16 -1 (-2075 1150)(-2075 1250);
WIRE 16 -1 (-3325 1150)(-2075 1150);
WIRE 16 -1 (-2075 1150)(-2075 1050);
WIRE 16 -1 (-2075 700)(-2075 1050);
WIRE 16 -1 (-3325 1050)(-2075 1050);
WIRE 16 -1 (-4625 5875)(-4625 5825);
WIRE 16 -1 (-4625 5950)(-4625 5875);
WIRE 16 -1 (-4625 5875)(-4800 5875);
WIRE 16 -1 (-4625 5825)(-4800 5825);
WIRE 16 -1 (-4625 5325)(-4625 5250);
WIRE 16 -1 (-4625 5375)(-4625 5325);
WIRE 16 -1 (-4625 5325)(-4800 5325);
WIRE 16 -1 (-4625 5250)(-4800 5250);
WIRE 16 -1 (-4625 5475)(-4625 5375);
WIRE 16 -1 (-4625 5375)(-4800 5375);
WIRE 16 -1 (-4800 4425)(-4600 4425);
WIRE 16 -1 (-4600 4425)(-4600 4475);
WIRE 16 -1 (-4600 4975)(-4600 4475);
WIRE 16 -1 (-4800 4475)(-4600 4475);
WIRE 16 -1 (-6950 2975)(-6775 2975);
WIRE 16 -1 (-6775 3050)(-6775 2975);
WIRE 16 -1 (-6950 3050)(-6775 3050);
WIRE 16 -1 (-6775 3100)(-6775 3050);
WIRE 16 -1 (-6775 3250)(-6775 3100);
WIRE 16 -1 (-6950 3100)(-6775 3100);
WIRE 16 -1 (-7125 3875)(-8150 3875);
FORCEPROP 2 LAST SIG_NAME P3V3_E1S_2_EN_R
J 0
(-8025 3885);
DISPLAY 0.489362 (-8025 3885);
WIRE 16 -1 (-7150 3050)(-8150 3050);
FORCEPROP 2 LAST SIG_NAME CPLD_PROGRAMN
J 0
(-8025 3060);
DISPLAY 0.489362 (-8025 3060);
WIRE 16 -1 (-7125 5775)(-8125 5775);
FORCEPROP 2 LAST SIG_NAME HSC_GPIO2_PLD_N
J 0
(-8025 5785);
DISPLAY 0.489362 (-8025 5785);
WIRE 16 -1 (-7125 5725)(-8125 5725);
FORCEPROP 2 LAST SIG_NAME SCM_USB_OC_N
J 0
(-8025 5735);
DISPLAY 0.489362 (-8025 5735);
WIRE 16 -1 (-7125 5825)(-8125 5825);
FORCEPROP 2 LAST SIG_NAME HSC_GPIO1_PLD_N
J 0
(-8025 5835);
DISPLAY 0.489362 (-8025 5835);
WIRE 16 -1 (-8125 5875)(-7125 5875);
FORCEPROP 0 LAST SIG_NAME SMB_SLOT1_ALERT_R_N
J 0
(-8035 5885);
DISPLAY 0.489362 (-8035 5885);
WIRE 16 -1 (-8125 5925)(-7125 5925);
FORCEPROP 0 LAST SIG_NAME SMB_SLOT2_ALERT_R_N
J 0
(-8035 5935);
DISPLAY 0.489362 (-8035 5935);
WIRE 16 -1 (-8125 5975)(-7125 5975);
FORCEPROP 0 LAST SIG_NAME SLOT1_CLKREQ_0_R_N
J 0
(-8035 5985);
DISPLAY 0.489362 (-8035 5985);
WIRE 16 -1 (-8125 6025)(-7125 6025);
FORCEPROP 0 LAST SIG_NAME SLOT1_CLKREQ_1_R_N
J 0
(-8035 6035);
DISPLAY 0.489362 (-8035 6035);
WIRE 16 -1 (-8125 6075)(-7125 6075);
FORCEPROP 0 LAST SIG_NAME SLOT2_CLKREQ_0_R_N
J 0
(-8035 6085);
DISPLAY 0.489362 (-8035 6085);
WIRE 16 -1 (-7125 3925)(-8150 3925);
FORCEPROP 2 LAST SIG_NAME P3V3_E1S_1_EN_R
J 0
(-8025 3935);
DISPLAY 0.489362 (-8025 3935);
WIRE 16 -1 (-7125 3775)(-8150 3775);
FORCEPROP 2 LAST SIG_NAME P3V3_E1S_4_EN_R
J 0
(-8025 3785);
DISPLAY 0.489362 (-8025 3785);
WIRE 16 -1 (-7125 3825)(-8150 3825);
FORCEPROP 2 LAST SIG_NAME P3V3_E1S_3_EN_R
J 0
(-8025 3835);
DISPLAY 0.489362 (-8025 3835);
WIRE 16 -1 (-8150 3625)(-7125 3625);
FORCEPROP 2 LAST SIG_NAME P3V3_OCP_EN_R
J 0
(-8025 3635);
DISPLAY 0.489362 (-8025 3635);
WIRE 16 -1 (-7125 3575)(-8150 3575);
FORCEPROP 2 LAST SIG_NAME P12V_OCP_EN_R
J 0
(-8025 3585);
DISPLAY 0.489362 (-8025 3585);
WIRE 16 -1 (-7150 3100)(-8150 3100);
FORCEPROP 2 LAST SIG_NAME CPLD_JTAG_EN
J 0
(-8025 3110);
DISPLAY 0.489362 (-8025 3110);
WIRE 16 -1 (-8125 6125)(-7125 6125);
FORCEPROP 0 LAST SIG_NAME SLOT2_CLKREQ_1_R_N
J 0
(-8035 6135);
DISPLAY 0.489362 (-8035 6135);
WIRE 16 -1 (-6050 5825)(-5000 5825);
FORCEPROP 2 LAST SIG_NAME FM_P1_PCC1_N
J 0
(-5825 5835);
DISPLAY 0.489362 (-5825 5835);
WIRE 16 -1 (-6050 5875)(-5000 5875);
FORCEPROP 2 LAST SIG_NAME FM_P1_PCC0_N
J 0
(-5825 5885);
DISPLAY 0.489362 (-5825 5885);
WIRE 16 -1 (-5000 5375)(-6025 5375);
FORCEPROP 2 LAST SIG_NAME FM_P0_PCC0_N
J 0
(-5800 5385);
DISPLAY 0.489362 (-5800 5385);
WIRE 16 -1 (-5000 5325)(-6025 5325);
FORCEPROP 2 LAST SIG_NAME FM_P0_PCC1_N
J 0
(-5800 5335);
DISPLAY 0.489362 (-5800 5335);
WIRE 16 -1 (-5000 5250)(-6025 5250);
FORCEPROP 2 LAST SIG_NAME RST_CPU0_KBRST_R_N
J 0
(-5800 5260);
DISPLAY 0.489362 (-5800 5260);
WIRE 16 -1 (-5000 4475)(-6000 4475);
FORCEPROP 2 LAST SIG_NAME FM_CLKREQ_M2_1_N
J 0
(-5900 4485);
DISPLAY 0.489362 (-5900 4485);
WIRE 16 -1 (-5000 4425)(-6000 4425);
FORCEPROP 2 LAST SIG_NAME FM_CLKREQ_M2_2_N
J 0
(-5900 4435);
DISPLAY 0.489362 (-5900 4435);
WIRE 16 -1 (-3675 3325)(-3675 3650);
WIRE 16 -1 (-2250 3650)(-3675 3650);
FORCEPROP 2 LAST SIG_NAME FM_I3C_CPU0_MUX0_OE_N
J 0
(-2935 3660);
DISPLAY 0.489362 (-2935 3660);
WIRE 16 -1 (-3475 3325)(-3475 3600);
WIRE 16 -1 (-2250 3600)(-3475 3600);
FORCEPROP 2 LAST SIG_NAME FM_I3C_CPU0_MUX1_OE_N
J 0
(-2935 3610);
DISPLAY 0.489362 (-2935 3610);
WIRE 16 -1 (-3275 3325)(-3275 3550);
WIRE 16 -1 (-2250 3550)(-3275 3550);
FORCEPROP 2 LAST SIG_NAME FM_I3C_CPU1_MUX0_OE_N
J 0
(-2935 3560);
DISPLAY 0.489362 (-2935 3560);
WIRE 16 -1 (-3050 3500)(-2250 3500);
FORCEPROP 2 LAST SIG_NAME FM_I3C_CPU1_MUX1_OE_N
J 0
(-2935 3510);
DISPLAY 0.489362 (-2935 3510);
WIRE 16 -1 (-3050 3325)(-3050 3500);
WIRE 16 -1 (-3075 6100)(-2050 6100);
FORCEPROP 2 LAST SIG_NAME RST_CPU1_PERST0_N
J 0
(-2600 6110);
DISPLAY 0.489362 (-2600 6110);
WIRE 16 -1 (-3075 5875)(-3075 6100);
WIRE 16 -1 (-2850 5875)(-2850 6050);
WIRE 16 -1 (-2050 6050)(-2850 6050);
FORCEPROP 2 LAST SIG_NAME RST_CPU1_PERST1_N
J 0
(-2600 6060);
DISPLAY 0.489362 (-2600 6060);
WIRE 16 -1 (-3475 6200)(-2050 6200);
FORCEPROP 2 LAST SIG_NAME RST_CPU0_PERST0_N
J 0
(-2600 6210);
DISPLAY 0.489362 (-2600 6210);
WIRE 16 -1 (-3475 5875)(-3475 6200);
WIRE 16 -1 (-3275 6150)(-2050 6150);
FORCEPROP 2 LAST SIG_NAME RST_CPU0_PERST1_N
J 0
(-2600 6160);
DISPLAY 0.489362 (-2600 6160);
WIRE 16 -1 (-3275 5875)(-3275 6150);
WIRE 16 -1 (-1425 5125)(-3475 5125);
FORCEPROP 2 LAST SIG_NAME RST_PERST_E1S_2_N
J 0
(-2025 5135);
DISPLAY 0.489362 (-2025 5135);
WIRE 16 -1 (-3475 5125)(-3475 4550);
WIRE 16 -1 (-1425 5175)(-3600 5175);
FORCEPROP 2 LAST SIG_NAME RST_PERST_E1S_1_N
J 0
(-2025 5185);
DISPLAY 0.489362 (-2025 5185);
WIRE 16 -1 (-3600 5175)(-3600 4550);
WIRE 16 -1 (-1425 5075)(-3350 5075);
FORCEPROP 2 LAST SIG_NAME RST_PERST_E1S_3_N
J 0
(-2025 5085);
DISPLAY 0.489362 (-2025 5085);
WIRE 16 -1 (-3350 5075)(-3350 4550);
WIRE 16 -1 (-3100 4550)(-3100 4975);
WIRE 16 -1 (-1425 4975)(-3100 4975);
FORCEPROP 2 LAST SIG_NAME RST_PERST_M2_1_N
J 0
(-2025 4985);
DISPLAY 0.489362 (-2025 4985);
WIRE 16 -1 (-1425 5025)(-3225 5025);
FORCEPROP 2 LAST SIG_NAME RST_PERST_E1S_4_N
J 0
(-2025 5035);
DISPLAY 0.489362 (-2025 5035);
WIRE 16 -1 (-3225 5025)(-3225 4550);
WIRE 16 -1 (-1425 4925)(-2975 4925);
FORCEPROP 2 LAST SIG_NAME RST_PERST_M2_2_N
J 0
(-2025 4935);
DISPLAY 0.489362 (-2025 4935);
WIRE 16 -1 (-2975 4925)(-2975 4550);
WIRE 16 -1 (-1425 4825)(-2700 4825);
FORCEPROP 2 LAST SIG_NAME RST_PERST_SLOT1_1_N
J 0
(-2025 4835);
DISPLAY 0.489362 (-2025 4835);
WIRE 16 -1 (-2700 4825)(-2700 4550);
WIRE 16 -1 (-1425 4875)(-2825 4875);
FORCEPROP 2 LAST SIG_NAME RST_PERST_SLOT1_0_N
J 0
(-2025 4885);
DISPLAY 0.489362 (-2025 4885);
WIRE 16 -1 (-2825 4875)(-2825 4550);
WIRE 16 -1 (-1425 4775)(-2575 4775);
FORCEPROP 2 LAST SIG_NAME RST_PERST_SLOT2_0_N
J 0
(-2025 4785);
DISPLAY 0.489362 (-2025 4785);
WIRE 16 -1 (-2575 4775)(-2575 4550);
WIRE 16 -1 (-1425 4675)(-2325 4675);
FORCEPROP 2 LAST SIG_NAME RST_PERST_SLOT3_N
J 0
(-2025 4685);
DISPLAY 0.489362 (-2025 4685);
WIRE 16 -1 (-2325 4675)(-2325 4550);
WIRE 16 -1 (-1425 4725)(-2450 4725);
FORCEPROP 2 LAST SIG_NAME RST_PERST_SLOT2_1_N
J 0
(-2025 4735);
DISPLAY 0.489362 (-2025 4735);
WIRE 16 -1 (-2450 4725)(-2450 4550);
DOT 1 (-6775 4725);
DOT 1 (-6775 4800);
DOT 1 (-6775 4850);
DOT 1 (-6775 4675);
DOT 1 (-6775 4625);
DOT 1 (-6775 5025);
DOT 1 (-6775 5100);
DOT 1 (-6775 4975);
DOT 1 (-6775 5225);
DOT 1 (-6775 5500);
DOT 1 (-6775 5300);
DOT 1 (-6775 5450);
DOT 1 (-6775 5350);
DOT 1 (-6775 5400);
DOT 1 (-6775 5550);
DOT 1 (-3800 1550);
DOT 1 (-3800 1650);
DOT 1 (-6800 5775);
DOT 1 (-6800 5825);
DOT 1 (-6800 5875);
DOT 1 (-3800 1250);
DOT 1 (-3800 1950);
DOT 1 (-6775 4075);
DOT 1 (-6800 6025);
DOT 1 (-6775 4300);
DOT 1 (-6775 3625);
DOT 1 (-7050 1450);
DOT 1 (-7300 1950);
DOT 1 (-7050 1950);
DOT 1 (-6450 1425);
DOT 1 (-6450 1225);
DOT 1 (-6450 1625);
DOT 1 (-6100 950);
DOT 1 (-5725 950);
DOT 1 (-5375 950);
DOT 1 (-6100 2000);
DOT 1 (-5375 2000);
DOT 1 (-5725 2000);
DOT 1 (-5075 1425);
DOT 1 (-5075 1225);
DOT 1 (-5075 1625);
DOT 1 (-5075 1825);
DOT 1 (-6800 6075);
DOT 1 (-6800 5925);
DOT 1 (-6800 5975);
DOT 1 (-6800 6125);
DOT 1 (-4600 4475);
DOT 1 (-6775 3925);
DOT 1 (-1550 1500);
DOT 1 (-2075 1350);
DOT 1 (-2075 1650);
DOT 1 (-1550 1400);
DOT 1 (-1550 1800);
DOT 1 (-350 1700);
DOT 1 (-350 1600);
DOT 1 (-350 1400);
DOT 1 (-350 1500);
DOT 1 (-350 1300);
DOT 1 (-350 1200);
DOT 1 (-350 1100);
DOT 1 (-350 1000);
DOT 1 (-350 900);
DOT 1 (-350 800);
DOT 1 (-350 700);
DOT 1 (-350 600);
DOT 1 (-1550 1600);
DOT 1 (-1550 1700);
DOT 1 (-1550 1300);
DOT 1 (-2075 1850);
DOT 1 (-2075 1750);
DOT 1 (-2075 1550);
DOT 1 (-2075 1250);
DOT 1 (-1550 1200);
DOT 1 (-1550 1100);
DOT 1 (-1550 1000);
DOT 1 (-1550 800);
DOT 1 (-1550 600);
DOT 1 (-1550 700);
DOT 1 (-2075 1150);
DOT 1 (-2075 1050);
DOT 1 (-3800 1850);
DOT 1 (-3800 1750);
DOT 1 (-3800 1350);
DOT 1 (-3800 1150);
DOT 1 (-4625 5875);
DOT 1 (-4625 5375);
DOT 1 (-4625 5325);
DOT 1 (-6775 4550);
DOT 1 (-6775 4400);
DOT 1 (-6775 4500);
DOT 1 (-6775 4450);
DOT 1 (-6775 4175);
DOT 1 (-6775 3875);
DOT 1 (-6775 3775);
DOT 1 (-1550 900);
DOT 1 (-6775 4125);
DOT 1 (-6775 3825);
DOT 1 (-6775 4025);
DOT 1 (-6775 3100);
DOT 1 (-6775 3050);
DOT 1 (-7575 1550);
DOT 1 (-7300 1500);
DOT 1 (-6450 1825);
FORCENOTE
1
(-5900 1500) 0;
DISPLAY LEFT (-5900 1500);
DISPLAY 1.021277 (-5900 1500);
PAINT WHITE (-5900 1500);
FORCENOTE
0
(-5575 1500) 0;
DISPLAY LEFT (-5575 1500);
DISPLAY 1.021277 (-5575 1500);
PAINT WHITE (-5575 1500);
FORCENOTE
0
(-5225 1500) 0;
DISPLAY LEFT (-5225 1500);
DISPLAY 1.021277 (-5225 1500);
PAINT WHITE (-5225 1500);
FORCENOTE
DV
(-6350 1300) 0;
DISPLAY LEFT (-6350 1300);
DISPLAY 1.021277 (-6350 1300);
PAINT WHITE (-6350 1300);
FORCENOTE
EV
(-6350 1675) 0;
DISPLAY LEFT (-6350 1675);
DISPLAY 1.021277 (-6350 1675);
PAINT WHITE (-6350 1675);
FORCENOTE
EV1
(-6350 1500) 0;
DISPLAY LEFT (-6350 1500);
DISPLAY 1.021277 (-6350 1500);
PAINT WHITE (-6350 1500);
FORCENOTE
0
(-5900 1300) 0;
DISPLAY LEFT (-5900 1300);
DISPLAY 1.021277 (-5900 1300);
PAINT WHITE (-5900 1300);
FORCENOTE
1
(-5900 1050) 0;
DISPLAY LEFT (-5900 1050);
DISPLAY 1.021277 (-5900 1050);
PAINT WHITE (-5900 1050);
FORCENOTE
0
(-5900 1700) 0;
DISPLAY LEFT (-5900 1700);
DISPLAY 1.021277 (-5900 1700);
PAINT WHITE (-5900 1700);
FORCENOTE
ID0
(-5975 1900) 0;
DISPLAY LEFT (-5975 1900);
DISPLAY 1.021277 (-5975 1900);
PAINT WHITE (-5975 1900);
FORCENOTE
1
(-5575 1050) 0;
DISPLAY LEFT (-5575 1050);
DISPLAY 1.021277 (-5575 1050);
PAINT WHITE (-5575 1050);
FORCENOTE
1
(-5575 1300) 0;
DISPLAY LEFT (-5575 1300);
DISPLAY 1.021277 (-5575 1300);
PAINT WHITE (-5575 1300);
FORCENOTE
ID1
(-5625 1900) 0;
DISPLAY LEFT (-5625 1900);
DISPLAY 1.021277 (-5625 1900);
PAINT WHITE (-5625 1900);
FORCENOTE
0
(-5575 1700) 0;
DISPLAY LEFT (-5575 1700);
DISPLAY 1.021277 (-5575 1700);
PAINT WHITE (-5575 1700);
FORCENOTE
0
(-5225 1050) 0;
DISPLAY LEFT (-5225 1050);
DISPLAY 1.021277 (-5225 1050);
PAINT WHITE (-5225 1050);
FORCENOTE
0
(-5225 1300) 0;
DISPLAY LEFT (-5225 1300);
DISPLAY 1.021277 (-5225 1300);
PAINT WHITE (-5225 1300);
FORCENOTE
0
(-5225 1700) 0;
DISPLAY LEFT (-5225 1700);
DISPLAY 1.021277 (-5225 1700);
PAINT WHITE (-5225 1700);
FORCENOTE
ID2
(-5275 1900) 0;
DISPLAY LEFT (-5275 1900);
DISPLAY 1.021277 (-5275 1900);
PAINT WHITE (-5275 1900);
FORCENOTE
PV
(-6350 1050) 0;
DISPLAY LEFT (-6350 1050);
DISPLAY 1.021277 (-6350 1050);
PAINT WHITE (-6350 1050);
QUIT
